(kicad_sch
	(version 20250114)
	(generator "eeschema")
	(generator_version "9.0")
	(paper "A3")
	(title_block
		(title "RDIMM DDR5 Tester")
		(date "2026-05-21")
		(rev "2.2.0")
		(company "Antmicro")
		(comment 1 "www.antmicro.com")
		(comment 2 "Antmicro")
	)
	(text "Clock source"
		(exclude_from_sim no)
		(at 305.054 210.312 0)
		(effects
			(font
				(size 2 2)
				(thickness 0.4978)
				(bold yes)
			)
			(justify left bottom)
		)
	)
	(text "VCCO (HP banks) max: 1.9V"
		(exclude_from_sim no)
		(at 13.97 21.59 0)
		(effects
			(font
				(size 1.27 1.27)
			)
			(justify left bottom)
		)
	)
	(text "Reference termination"
		(exclude_from_sim no)
		(at 193.548 211.836 0)
		(effects
			(font
				(size 2 2)
				(thickness 0.4978)
				(bold yes)
			)
			(justify left bottom)
		)
	)
	(text "HP Banks"
		(exclude_from_sim no)
		(at 13.335 18.415 0)
		(effects
			(font
				(size 3 3)
				(thickness 0.6)
				(bold yes)
			)
			(justify left bottom)
		)
	)
	(text "Pinout 1.1.1"
		(exclude_from_sim no)
		(at 386.334 208.026 0)
		(effects
			(font
				(size 2 2)
				(thickness 0.4)
				(bold yes)
			)
			(justify left bottom)
		)
	)
	(text "VREF"
		(exclude_from_sim no)
		(at 19.558 210.566 0)
		(effects
			(font
				(size 2 2)
				(thickness 0.4978)
				(bold yes)
			)
			(justify left bottom)
		)
	)
	(junction
		(at 83.82 234.95)
		(diameter 0)
		(color 0 0 0 0)
	)
	(junction
		(at 134.62 234.95)
		(diameter 0)
		(color 0 0 0 0)
	)
	(junction
		(at 93.98 234.95)
		(diameter 0)
		(color 0 0 0 0)
	)
	(junction
		(at 93.98 242.57)
		(diameter 0)
		(color 0 0 0 0)
	)
	(junction
		(at 345.44 236.22)
		(diameter 0)
		(color 0 0 0 0)
	)
	(junction
		(at 114.3 242.57)
		(diameter 0)
		(color 0 0 0 0)
	)
	(junction
		(at 134.62 242.57)
		(diameter 0)
		(color 0 0 0 0)
	)
	(junction
		(at 335.28 232.41)
		(diameter 0)
		(color 0 0 0 0)
	)
	(junction
		(at 114.3 234.95)
		(diameter 0)
		(color 0 0 0 0)
	)
	(junction
		(at 46.99 234.95)
		(diameter 0)
		(color 0 0 0 0)
	)
	(junction
		(at 154.94 242.57)
		(diameter 0)
		(color 0 0 0 0)
	)
	(no_connect
		(at 243.84 189.23)
	)
	(no_connect
		(at 345.44 111.76)
	)
	(no_connect
		(at 52.07 154.94)
	)
	(no_connect
		(at 243.84 156.21)
	)
	(no_connect
		(at 52.07 187.96)
	)
	(no_connect
		(at 345.44 124.46)
	)
	(no_connect
		(at 345.44 127)
	)
	(no_connect
		(at 243.84 123.19)
	)
	(no_connect
		(at 345.44 154.94)
	)
	(no_connect
		(at 52.07 121.92)
	)
	(no_connect
		(at 345.44 121.92)
	)
	(no_connect
		(at 345.44 114.3)
	)
	(no_connect
		(at 345.44 185.42)
	)
	(no_connect
		(at 345.44 187.96)
	)
	(no_connect
		(at 345.44 157.48)
	)
	(no_connect
		(at 345.44 160.02)
	)
	(bus_entry
		(at 233.68 64.77)
		(size -2.54 -2.54)
		(stroke
			(width 0)
			(type default)
		)
	)
	(bus_entry
		(at 233.68 153.67)
		(size -2.54 -2.54)
		(stroke
			(width 0)
			(type default)
		)
	)
	(bus_entry
		(at 233.68 69.85)
		(size -2.54 -2.54)
		(stroke
			(width 0)
			(type default)
		)
	)
	(bus_entry
		(at 130.81 113.03)
		(size -2.54 -2.54)
		(stroke
			(width 0)
			(type default)
		)
	)
	(bus_entry
		(at 130.81 62.23)
		(size -2.54 -2.54)
		(stroke
			(width 0)
			(type default)
		)
	)
	(bus_entry
		(at 233.68 184.15)
		(size -2.54 -2.54)
		(stroke
			(width 0)
			(type default)
		)
	)
	(bus_entry
		(at 130.81 72.39)
		(size -2.54 -2.54)
		(stroke
			(width 0)
			(type default)
		)
	)
	(bus_entry
		(at 130.81 85.09)
		(size -2.54 -2.54)
		(stroke
			(width 0)
			(type default)
		)
	)
	(bus_entry
		(at 41.91 66.04)
		(size -2.54 -2.54)
		(stroke
			(width 0)
			(type default)
		)
	)
	(bus_entry
		(at 41.91 111.76)
		(size -2.54 -2.54)
		(stroke
			(width 0)
			(type default)
		)
	)
	(bus_entry
		(at 130.81 128.27)
		(size -2.54 -2.54)
		(stroke
			(width 0)
			(type default)
		)
	)
	(bus_entry
		(at 41.91 83.82)
		(size -2.54 -2.54)
		(stroke
			(width 0)
			(type default)
		)
	)
	(bus_entry
		(at 233.68 77.47)
		(size -2.54 -2.54)
		(stroke
			(width 0)
			(type default)
		)
	)
	(bus_entry
		(at 41.91 134.62)
		(size -2.54 -2.54)
		(stroke
			(width 0)
			(type default)
		)
	)
	(bus_entry
		(at 41.91 106.68)
		(size -2.54 -2.54)
		(stroke
			(width 0)
			(type default)
		)
	)
	(bus_entry
		(at 316.23 138.43)
		(size 1.27 1.27)
		(stroke
			(width 0)
			(type default)
		)
	)
	(bus_entry
		(at 316.23 82.55)
		(size 1.27 1.27)
		(stroke
			(width 0)
			(type default)
		)
	)
	(bus_entry
		(at 41.91 144.78)
		(size -2.54 -2.54)
		(stroke
			(width 0)
			(type default)
		)
	)
	(bus_entry
		(at 73.66 26.67)
		(size 2.54 2.54)
		(stroke
			(width 0)
			(type default)
		)
	)
	(bus_entry
		(at 316.23 64.77)
		(size 1.27 1.27)
		(stroke
			(width 0)
			(type default)
		)
	)
	(bus_entry
		(at 41.91 96.52)
		(size -2.54 -2.54)
		(stroke
			(width 0)
			(type default)
		)
	)
	(bus_entry
		(at 76.2 34.29)
		(size -2.54 -2.54)
		(stroke
			(width 0)
			(type default)
		)
	)
	(bus_entry
		(at 41.91 167.64)
		(size -2.54 -2.54)
		(stroke
			(width 0)
			(type default)
		)
	)
	(bus_entry
		(at 41.91 149.86)
		(size -2.54 -2.54)
		(stroke
			(width 0)
			(type default)
		)
	)
	(bus_entry
		(at 316.23 69.85)
		(size 1.27 1.27)
		(stroke
			(width 0)
			(type default)
		)
	)
	(bus_entry
		(at 233.68 158.75)
		(size -2.54 -2.54)
		(stroke
			(width 0)
			(type default)
		)
	)
	(bus_entry
		(at 130.81 135.89)
		(size -2.54 -2.54)
		(stroke
			(width 0)
			(type default)
		)
	)
	(bus_entry
		(at 233.68 181.61)
		(size -2.54 -2.54)
		(stroke
			(width 0)
			(type default)
		)
	)
	(bus_entry
		(at 130.81 146.05)
		(size -2.54 -2.54)
		(stroke
			(width 0)
			(type default)
		)
	)
	(bus_entry
		(at 316.23 62.23)
		(size 1.27 1.27)
		(stroke
			(width 0)
			(type default)
		)
	)
	(bus_entry
		(at 41.91 142.24)
		(size -2.54 -2.54)
		(stroke
			(width 0)
			(type default)
		)
	)
	(bus_entry
		(at 233.68 97.79)
		(size -2.54 -2.54)
		(stroke
			(width 0)
			(type default)
		)
	)
	(bus_entry
		(at 130.81 77.47)
		(size -2.54 -2.54)
		(stroke
			(width 0)
			(type default)
		)
	)
	(bus_entry
		(at 316.23 133.35)
		(size 1.27 1.27)
		(stroke
			(width 0)
			(type default)
		)
	)
	(bus_entry
		(at 41.91 86.36)
		(size -2.54 -2.54)
		(stroke
			(width 0)
			(type default)
		)
	)
	(bus_entry
		(at 41.91 73.66)
		(size -2.54 -2.54)
		(stroke
			(width 0)
			(type default)
		)
	)
	(bus_entry
		(at 233.68 125.73)
		(size -2.54 -2.54)
		(stroke
			(width 0)
			(type default)
		)
	)
	(bus_entry
		(at 233.68 118.11)
		(size -2.54 -2.54)
		(stroke
			(width 0)
			(type default)
		)
	)
	(bus_entry
		(at 233.68 179.07)
		(size -2.54 -2.54)
		(stroke
			(width 0)
			(type default)
		)
	)
	(bus_entry
		(at 130.81 118.11)
		(size -2.54 -2.54)
		(stroke
			(width 0)
			(type default)
		)
	)
	(bus_entry
		(at 41.91 99.06)
		(size -2.54 -2.54)
		(stroke
			(width 0)
			(type default)
		)
	)
	(bus_entry
		(at 41.91 93.98)
		(size -2.54 -2.54)
		(stroke
			(width 0)
			(type default)
		)
	)
	(bus_entry
		(at 130.81 64.77)
		(size -2.54 -2.54)
		(stroke
			(width 0)
			(type default)
		)
	)
	(bus_entry
		(at 130.81 173.99)
		(size -2.54 -2.54)
		(stroke
			(width 0)
			(type default)
		)
	)
	(bus_entry
		(at 41.91 170.18)
		(size -2.54 -2.54)
		(stroke
			(width 0)
			(type default)
		)
	)
	(bus_entry
		(at 233.68 100.33)
		(size -2.54 -2.54)
		(stroke
			(width 0)
			(type default)
		)
	)
	(bus_entry
		(at 233.68 168.91)
		(size -2.54 -2.54)
		(stroke
			(width 0)
			(type default)
		)
	)
	(bus_entry
		(at 316.23 181.61)
		(size 1.27 1.27)
		(stroke
			(width 0)
			(type default)
		)
	)
	(bus_entry
		(at 76.2 24.13)
		(size -2.54 -2.54)
		(stroke
			(width 0)
			(type default)
		)
	)
	(bus_entry
		(at 233.68 163.83)
		(size -2.54 -2.54)
		(stroke
			(width 0)
			(type default)
		)
	)
	(bus_entry
		(at 314.96 93.98)
		(size -2.54 -2.54)
		(stroke
			(width 0)
			(type default)
		)
	)
	(bus_entry
		(at 41.91 68.58)
		(size -2.54 -2.54)
		(stroke
			(width 0)
			(type default)
		)
	)
	(bus_entry
		(at 130.81 168.91)
		(size -2.54 -2.54)
		(stroke
			(width 0)
			(type default)
		)
	)
	(bus_entry
		(at 316.23 176.53)
		(size 1.27 1.27)
		(stroke
			(width 0)
			(type default)
		)
	)
	(bus_entry
		(at 130.81 181.61)
		(size -2.54 -2.54)
		(stroke
			(width 0)
			(type default)
		)
	)
	(bus_entry
		(at 314.96 101.6)
		(size -2.54 -2.54)
		(stroke
			(width 0)
			(type default)
		)
	)
	(bus_entry
		(at 316.23 161.29)
		(size 1.27 1.27)
		(stroke
			(width 0)
			(type default)
		)
	)
	(bus_entry
		(at 233.68 72.39)
		(size -2.54 -2.54)
		(stroke
			(width 0)
			(type default)
		)
	)
	(bus_entry
		(at 130.81 120.65)
		(size -2.54 -2.54)
		(stroke
			(width 0)
			(type default)
		)
	)
	(bus_entry
		(at 130.81 100.33)
		(size -2.54 -2.54)
		(stroke
			(width 0)
			(type default)
		)
	)
	(bus_entry
		(at 130.81 163.83)
		(size -2.54 -2.54)
		(stroke
			(width 0)
			(type default)
		)
	)
	(bus_entry
		(at 41.91 162.56)
		(size -2.54 -2.54)
		(stroke
			(width 0)
			(type default)
		)
	)
	(bus_entry
		(at 316.23 146.05)
		(size 1.27 1.27)
		(stroke
			(width 0)
			(type default)
		)
	)
	(bus_entry
		(at 233.68 92.71)
		(size -2.54 -2.54)
		(stroke
			(width 0)
			(type default)
		)
	)
	(bus_entry
		(at 130.81 166.37)
		(size -2.54 -2.54)
		(stroke
			(width 0)
			(type default)
		)
	)
	(bus_entry
		(at 233.68 115.57)
		(size -2.54 -2.54)
		(stroke
			(width 0)
			(type default)
		)
	)
	(bus_entry
		(at 41.91 172.72)
		(size -2.54 -2.54)
		(stroke
			(width 0)
			(type default)
		)
	)
	(bus_entry
		(at 130.81 125.73)
		(size -2.54 -2.54)
		(stroke
			(width 0)
			(type default)
		)
	)
	(bus_entry
		(at 233.68 120.65)
		(size -2.54 -2.54)
		(stroke
			(width 0)
			(type default)
		)
	)
	(bus_entry
		(at 130.81 179.07)
		(size -2.54 -2.54)
		(stroke
			(width 0)
			(type default)
		)
	)
	(bus_entry
		(at 233.68 82.55)
		(size -2.54 -2.54)
		(stroke
			(width 0)
			(type default)
		)
	)
	(bus_entry
		(at 130.81 92.71)
		(size -2.54 -2.54)
		(stroke
			(width 0)
			(type default)
		)
	)
	(bus_entry
		(at 130.81 130.81)
		(size -2.54 -2.54)
		(stroke
			(width 0)
			(type default)
		)
	)
	(bus_entry
		(at 130.81 184.15)
		(size -2.54 -2.54)
		(stroke
			(width 0)
			(type default)
		)
	)
	(bus_entry
		(at 73.66 29.21)
		(size 2.54 2.54)
		(stroke
			(width 0)
			(type default)
		)
	)
	(bus_entry
		(at 41.91 101.6)
		(size -2.54 -2.54)
		(stroke
			(width 0)
			(type default)
		)
	)
	(bus_entry
		(at 41.91 78.74)
		(size -2.54 -2.54)
		(stroke
			(width 0)
			(type default)
		)
	)
	(bus_entry
		(at 316.23 74.93)
		(size 1.27 1.27)
		(stroke
			(width 0)
			(type default)
		)
	)
	(bus_entry
		(at 41.91 132.08)
		(size -2.54 -2.54)
		(stroke
			(width 0)
			(type default)
		)
	)
	(bus_entry
		(at 316.23 171.45)
		(size 1.27 1.27)
		(stroke
			(width 0)
			(type default)
		)
	)
	(bus_entry
		(at 233.68 62.23)
		(size -2.54 -2.54)
		(stroke
			(width 0)
			(type default)
		)
	)
	(bus_entry
		(at 316.23 77.47)
		(size 1.27 1.27)
		(stroke
			(width 0)
			(type default)
		)
	)
	(bus_entry
		(at 233.68 151.13)
		(size -2.54 -2.54)
		(stroke
			(width 0)
			(type default)
		)
	)
	(bus_entry
		(at 233.68 87.63)
		(size -2.54 -2.54)
		(stroke
			(width 0)
			(type default)
		)
	)
	(bus_entry
		(at 233.68 135.89)
		(size -2.54 -2.54)
		(stroke
			(width 0)
			(type default)
		)
	)
	(bus_entry
		(at 314.96 106.68)
		(size -2.54 -2.54)
		(stroke
			(width 0)
			(type default)
		)
	)
	(bus_entry
		(at 316.23 143.51)
		(size 1.27 1.27)
		(stroke
			(width 0)
			(type default)
		)
	)
	(bus_entry
		(at 41.91 157.48)
		(size -2.54 -2.54)
		(stroke
			(width 0)
			(type default)
		)
	)
	(bus_entry
		(at 130.81 153.67)
		(size -2.54 -2.54)
		(stroke
			(width 0)
			(type default)
		)
	)
	(bus_entry
		(at 130.81 95.25)
		(size -2.54 -2.54)
		(stroke
			(width 0)
			(type default)
		)
	)
	(bus_entry
		(at 130.81 80.01)
		(size -2.54 -2.54)
		(stroke
			(width 0)
			(type default)
		)
	)
	(bus_entry
		(at 130.81 148.59)
		(size -2.54 -2.54)
		(stroke
			(width 0)
			(type default)
		)
	)
	(bus_entry
		(at 130.81 67.31)
		(size -2.54 -2.54)
		(stroke
			(width 0)
			(type default)
		)
	)
	(bus_entry
		(at 130.81 171.45)
		(size -2.54 -2.54)
		(stroke
			(width 0)
			(type default)
		)
	)
	(bus_entry
		(at 41.91 137.16)
		(size -2.54 -2.54)
		(stroke
			(width 0)
			(type default)
		)
	)
	(bus_entry
		(at 76.2 26.67)
		(size -2.54 -2.54)
		(stroke
			(width 0)
			(type default)
		)
	)
	(bus_entry
		(at 233.68 102.87)
		(size -2.54 -2.54)
		(stroke
			(width 0)
			(type default)
		)
	)
	(bus_entry
		(at 130.81 102.87)
		(size -2.54 -2.54)
		(stroke
			(width 0)
			(type default)
		)
	)
	(bus_entry
		(at 316.23 179.07)
		(size 1.27 1.27)
		(stroke
			(width 0)
			(type default)
		)
	)
	(bus_entry
		(at 41.91 60.96)
		(size -2.54 -2.54)
		(stroke
			(width 0)
			(type default)
		)
	)
	(bus_entry
		(at 316.23 151.13)
		(size 1.27 1.27)
		(stroke
			(width 0)
			(type default)
		)
	)
	(bus_entry
		(at 316.23 57.15)
		(size 1.27 1.27)
		(stroke
			(width 0)
			(type default)
		)
	)
	(bus_entry
		(at 314.96 99.06)
		(size -2.54 -2.54)
		(stroke
			(width 0)
			(type default)
		)
	)
	(bus_entry
		(at 316.23 148.59)
		(size 1.27 1.27)
		(stroke
			(width 0)
			(type default)
		)
	)
	(bus_entry
		(at 130.81 87.63)
		(size -2.54 -2.54)
		(stroke
			(width 0)
			(type default)
		)
	)
	(bus_entry
		(at 41.91 71.12)
		(size -2.54 -2.54)
		(stroke
			(width 0)
			(type default)
		)
	)
	(bus_entry
		(at 41.91 109.22)
		(size -2.54 -2.54)
		(stroke
			(width 0)
			(type default)
		)
	)
	(bus_entry
		(at 314.96 96.52)
		(size -2.54 -2.54)
		(stroke
			(width 0)
			(type default)
		)
	)
	(bus_entry
		(at 130.81 151.13)
		(size -2.54 -2.54)
		(stroke
			(width 0)
			(type default)
		)
	)
	(bus_entry
		(at 233.68 107.95)
		(size -2.54 -2.54)
		(stroke
			(width 0)
			(type default)
		)
	)
	(bus_entry
		(at 41.91 114.3)
		(size -2.54 -2.54)
		(stroke
			(width 0)
			(type default)
		)
	)
	(bus_entry
		(at 233.68 173.99)
		(size -2.54 -2.54)
		(stroke
			(width 0)
			(type default)
		)
	)
	(bus_entry
		(at 233.68 130.81)
		(size -2.54 -2.54)
		(stroke
			(width 0)
			(type default)
		)
	)
	(bus_entry
		(at 41.91 124.46)
		(size -2.54 -2.54)
		(stroke
			(width 0)
			(type default)
		)
	)
	(bus_entry
		(at 316.23 140.97)
		(size 1.27 1.27)
		(stroke
			(width 0)
			(type default)
		)
	)
	(bus_entry
		(at 130.81 97.79)
		(size -2.54 -2.54)
		(stroke
			(width 0)
			(type default)
		)
	)
	(bus_entry
		(at 41.91 58.42)
		(size -2.54 -2.54)
		(stroke
			(width 0)
			(type default)
		)
	)
	(bus_entry
		(at 41.91 139.7)
		(size -2.54 -2.54)
		(stroke
			(width 0)
			(type default)
		)
	)
	(bus_entry
		(at 130.81 158.75)
		(size -2.54 -2.54)
		(stroke
			(width 0)
			(type default)
		)
	)
	(bus_entry
		(at 41.91 104.14)
		(size -2.54 -2.54)
		(stroke
			(width 0)
			(type default)
		)
	)
	(bus_entry
		(at 316.23 166.37)
		(size 1.27 1.27)
		(stroke
			(width 0)
			(type default)
		)
	)
	(bus_entry
		(at 41.91 180.34)
		(size -2.54 -2.54)
		(stroke
			(width 0)
			(type default)
		)
	)
	(bus_entry
		(at 130.81 115.57)
		(size -2.54 -2.54)
		(stroke
			(width 0)
			(type default)
		)
	)
	(bus_entry
		(at 233.68 140.97)
		(size -2.54 -2.54)
		(stroke
			(width 0)
			(type default)
		)
	)
	(bus_entry
		(at 41.91 177.8)
		(size -2.54 -2.54)
		(stroke
			(width 0)
			(type default)
		)
	)
	(bus_entry
		(at 41.91 91.44)
		(size -2.54 -2.54)
		(stroke
			(width 0)
			(type default)
		)
	)
	(bus_entry
		(at 233.68 110.49)
		(size -2.54 -2.54)
		(stroke
			(width 0)
			(type default)
		)
	)
	(bus_entry
		(at 41.91 76.2)
		(size -2.54 -2.54)
		(stroke
			(width 0)
			(type default)
		)
	)
	(bus_entry
		(at 130.81 105.41)
		(size -2.54 -2.54)
		(stroke
			(width 0)
			(type default)
		)
	)
	(bus_entry
		(at 233.68 166.37)
		(size -2.54 -2.54)
		(stroke
			(width 0)
			(type default)
		)
	)
	(bus_entry
		(at 41.91 129.54)
		(size -2.54 -2.54)
		(stroke
			(width 0)
			(type default)
		)
	)
	(bus_entry
		(at 233.68 105.41)
		(size -2.54 -2.54)
		(stroke
			(width 0)
			(type default)
		)
	)
	(bus_entry
		(at 41.91 175.26)
		(size -2.54 -2.54)
		(stroke
			(width 0)
			(type default)
		)
	)
	(bus_entry
		(at 314.96 104.14)
		(size -2.54 -2.54)
		(stroke
			(width 0)
			(type default)
		)
	)
	(bus_entry
		(at 130.81 69.85)
		(size -2.54 -2.54)
		(stroke
			(width 0)
			(type default)
		)
	)
	(bus_entry
		(at 130.81 74.93)
		(size -2.54 -2.54)
		(stroke
			(width 0)
			(type default)
		)
	)
	(bus_entry
		(at 233.68 171.45)
		(size -2.54 -2.54)
		(stroke
			(width 0)
			(type default)
		)
	)
	(bus_entry
		(at 233.68 113.03)
		(size -2.54 -2.54)
		(stroke
			(width 0)
			(type default)
		)
	)
	(bus_entry
		(at 316.23 59.69)
		(size 1.27 1.27)
		(stroke
			(width 0)
			(type default)
		)
	)
	(bus_entry
		(at 233.68 67.31)
		(size -2.54 -2.54)
		(stroke
			(width 0)
			(type default)
		)
	)
	(bus_entry
		(at 316.23 135.89)
		(size 1.27 1.27)
		(stroke
			(width 0)
			(type default)
		)
	)
	(bus_entry
		(at 41.91 116.84)
		(size -2.54 -2.54)
		(stroke
			(width 0)
			(type default)
		)
	)
	(bus_entry
		(at 41.91 160.02)
		(size -2.54 -2.54)
		(stroke
			(width 0)
			(type default)
		)
	)
	(bus_entry
		(at 316.23 80.01)
		(size 1.27 1.27)
		(stroke
			(width 0)
			(type default)
		)
	)
	(bus_entry
		(at 316.23 173.99)
		(size 1.27 1.27)
		(stroke
			(width 0)
			(type default)
		)
	)
	(bus_entry
		(at 316.23 90.17)
		(size 1.27 1.27)
		(stroke
			(width 0)
			(type default)
		)
	)
	(bus_entry
		(at 130.81 161.29)
		(size -2.54 -2.54)
		(stroke
			(width 0)
			(type default)
		)
	)
	(bus_entry
		(at 130.81 82.55)
		(size -2.54 -2.54)
		(stroke
			(width 0)
			(type default)
		)
	)
	(bus_entry
		(at 316.23 67.31)
		(size 1.27 1.27)
		(stroke
			(width 0)
			(type default)
		)
	)
	(bus_entry
		(at 233.68 128.27)
		(size -2.54 -2.54)
		(stroke
			(width 0)
			(type default)
		)
	)
	(bus_entry
		(at 41.91 119.38)
		(size -2.54 -2.54)
		(stroke
			(width 0)
			(type default)
		)
	)
	(bus_entry
		(at 41.91 147.32)
		(size -2.54 -2.54)
		(stroke
			(width 0)
			(type default)
		)
	)
	(bus_entry
		(at 130.81 133.35)
		(size -2.54 -2.54)
		(stroke
			(width 0)
			(type default)
		)
	)
	(bus_entry
		(at 41.91 165.1)
		(size -2.54 -2.54)
		(stroke
			(width 0)
			(type default)
		)
	)
	(bus_entry
		(at 233.68 59.69)
		(size -2.54 -2.54)
		(stroke
			(width 0)
			(type default)
		)
	)
	(bus_entry
		(at 233.68 143.51)
		(size -2.54 -2.54)
		(stroke
			(width 0)
			(type default)
		)
	)
	(bus_entry
		(at 316.23 168.91)
		(size 1.27 1.27)
		(stroke
			(width 0)
			(type default)
		)
	)
	(bus_entry
		(at 233.68 186.69)
		(size -2.54 -2.54)
		(stroke
			(width 0)
			(type default)
		)
	)
	(bus_entry
		(at 130.81 59.69)
		(size -2.54 -2.54)
		(stroke
			(width 0)
			(type default)
		)
	)
	(bus_entry
		(at 233.68 133.35)
		(size -2.54 -2.54)
		(stroke
			(width 0)
			(type default)
		)
	)
	(bus_entry
		(at 316.23 85.09)
		(size 1.27 1.27)
		(stroke
			(width 0)
			(type default)
		)
	)
	(bus_entry
		(at 41.91 182.88)
		(size -2.54 -2.54)
		(stroke
			(width 0)
			(type default)
		)
	)
	(bus_entry
		(at 41.91 185.42)
		(size -2.54 -2.54)
		(stroke
			(width 0)
			(type default)
		)
	)
	(bus_entry
		(at 233.68 85.09)
		(size -2.54 -2.54)
		(stroke
			(width 0)
			(type default)
		)
	)
	(bus_entry
		(at 41.91 63.5)
		(size -2.54 -2.54)
		(stroke
			(width 0)
			(type default)
		)
	)
	(bus_entry
		(at 316.23 72.39)
		(size 1.27 1.27)
		(stroke
			(width 0)
			(type default)
		)
	)
	(bus_entry
		(at 233.68 95.25)
		(size -2.54 -2.54)
		(stroke
			(width 0)
			(type default)
		)
	)
	(bus_entry
		(at 130.81 176.53)
		(size -2.54 -2.54)
		(stroke
			(width 0)
			(type default)
		)
	)
	(bus_entry
		(at 316.23 163.83)
		(size 1.27 1.27)
		(stroke
			(width 0)
			(type default)
		)
	)
	(bus_entry
		(at 41.91 81.28)
		(size -2.54 -2.54)
		(stroke
			(width 0)
			(type default)
		)
	)
	(bus_entry
		(at 233.68 146.05)
		(size -2.54 -2.54)
		(stroke
			(width 0)
			(type default)
		)
	)
	(bus_entry
		(at 233.68 80.01)
		(size -2.54 -2.54)
		(stroke
			(width 0)
			(type default)
		)
	)
	(bus_entry
		(at 73.66 38.1)
		(size 1.27 1.27)
		(stroke
			(width 0)
			(type default)
		)
	)
	(bus_entry
		(at 76.2 36.83)
		(size -2.54 -2.54)
		(stroke
			(width 0)
			(type default)
		)
	)
	(bus_entry
		(at 41.91 152.4)
		(size -2.54 -2.54)
		(stroke
			(width 0)
			(type default)
		)
	)
	(bus_entry
		(at 233.68 161.29)
		(size -2.54 -2.54)
		(stroke
			(width 0)
			(type default)
		)
	)
	(bus_entry
		(at 130.81 186.69)
		(size -2.54 -2.54)
		(stroke
			(width 0)
			(type default)
		)
	)
	(bus_entry
		(at 41.91 127)
		(size -2.54 -2.54)
		(stroke
			(width 0)
			(type default)
		)
	)
	(bus_entry
		(at 312.42 106.68)
		(size 2.54 2.54)
		(stroke
			(width 0)
			(type default)
		)
	)
	(bus_entry
		(at 233.68 148.59)
		(size -2.54 -2.54)
		(stroke
			(width 0)
			(type default)
		)
	)
	(bus_entry
		(at 233.68 176.53)
		(size -2.54 -2.54)
		(stroke
			(width 0)
			(type default)
		)
	)
	(bus_entry
		(at 233.68 74.93)
		(size -2.54 -2.54)
		(stroke
			(width 0)
			(type default)
		)
	)
	(bus_entry
		(at 233.68 138.43)
		(size -2.54 -2.54)
		(stroke
			(width 0)
			(type default)
		)
	)
	(bus_entry
		(at 130.81 138.43)
		(size -2.54 -2.54)
		(stroke
			(width 0)
			(type default)
		)
	)
	(bus
		(pts
			(xy 316.23 62.23) (xy 316.23 64.77)
		)
		(stroke
			(width 0)
			(type default)
		)
	)
	(wire
		(pts
			(xy 144.78 242.57) (xy 154.94 242.57)
		)
		(stroke
			(width 0)
			(type default)
		)
	)
	(wire
		(pts
			(xy 83.82 242.57) (xy 93.98 242.57)
		)
		(stroke
			(width 0)
			(type default)
		)
	)
	(wire
		(pts
			(xy 41.91 88.9) (xy 52.07 88.9)
		)
		(stroke
			(width 0)
			(type default)
		)
	)
	(bus
		(pts
			(xy 231.14 62.23) (xy 231.14 64.77)
		)
		(stroke
			(width 0)
			(type default)
		)
	)
	(wire
		(pts
			(xy 314.96 99.06) (xy 345.44 99.06)
		)
		(stroke
			(width 0)
			(type default)
		)
	)
	(wire
		(pts
			(xy 233.68 179.07) (xy 243.84 179.07)
		)
		(stroke
			(width 0)
			(type default)
		)
	)
	(bus
		(pts
			(xy 128.27 171.45) (xy 128.27 173.99)
		)
		(stroke
			(width 0)
			(type default)
		)
	)
	(wire
		(pts
			(xy 41.91 71.12) (xy 52.07 71.12)
		)
		(stroke
			(width 0)
			(type default)
		)
	)
	(wire
		(pts
			(xy 41.91 60.96) (xy 52.07 60.96)
		)
		(stroke
			(width 0)
			(type default)
		)
	)
	(bus
		(pts
			(xy 128.27 163.83) (xy 128.27 166.37)
		)
		(stroke
			(width 0)
			(type default)
		)
	)
	(wire
		(pts
			(xy 41.91 119.38) (xy 52.07 119.38)
		)
		(stroke
			(width 0)
			(type default)
		)
	)
	(bus
		(pts
			(xy 312.42 87.63) (xy 312.42 91.44)
		)
		(stroke
			(width 0)
			(type default)
		)
	)
	(wire
		(pts
			(xy 233.68 69.85) (xy 243.84 69.85)
		)
		(stroke
			(width 0)
			(type default)
		)
	)
	(wire
		(pts
			(xy 41.91 73.66) (xy 52.07 73.66)
		)
		(stroke
			(width 0)
			(type default)
		)
	)
	(wire
		(pts
			(xy 41.91 76.2) (xy 52.07 76.2)
		)
		(stroke
			(width 0)
			(type default)
		)
	)
	(bus
		(pts
			(xy 39.37 162.56) (xy 39.37 165.1)
		)
		(stroke
			(width 0)
			(type default)
		)
	)
	(bus
		(pts
			(xy 316.23 77.47) (xy 316.23 80.01)
		)
		(stroke
			(width 0)
			(type default)
		)
	)
	(wire
		(pts
			(xy 344.17 50.8) (xy 345.44 50.8)
		)
		(stroke
			(width 0)
			(type default)
		)
	)
	(wire
		(pts
			(xy 41.91 68.58) (xy 52.07 68.58)
		)
		(stroke
			(width 0)
			(type default)
		)
	)
	(wire
		(pts
			(xy 76.2 24.13) (xy 95.25 24.13)
		)
		(stroke
			(width 0)
			(type default)
		)
	)
	(wire
		(pts
			(xy 134.62 248.92) (xy 134.62 250.19)
		)
		(stroke
			(width 0)
			(type default)
		)
	)
	(wire
		(pts
			(xy 130.81 148.59) (xy 148.59 148.59)
		)
		(stroke
			(width 0)
			(type default)
		)
	)
	(bus
		(pts
			(xy 231.14 82.55) (xy 231.14 85.09)
		)
		(stroke
			(width 0)
			(type default)
		)
	)
	(wire
		(pts
			(xy 144.78 250.19) (xy 144.78 248.92)
		)
		(stroke
			(width 0)
			(type default)
		)
	)
	(wire
		(pts
			(xy 317.5 144.78) (xy 345.44 144.78)
		)
		(stroke
			(width 0)
			(type default)
		)
	)
	(bus
		(pts
			(xy 231.14 77.47) (xy 231.14 80.01)
		)
		(stroke
			(width 0)
			(type default)
		)
	)
	(wire
		(pts
			(xy 233.68 128.27) (xy 243.84 128.27)
		)
		(stroke
			(width 0)
			(type default)
		)
	)
	(bus
		(pts
			(xy 39.37 58.42) (xy 39.37 60.96)
		)
		(stroke
			(width 0)
			(type default)
		)
	)
	(wire
		(pts
			(xy 41.91 93.98) (xy 52.07 93.98)
		)
		(stroke
			(width 0)
			(type default)
		)
	)
	(wire
		(pts
			(xy 154.94 241.3) (xy 154.94 242.57)
		)
		(stroke
			(width 0)
			(type default)
		)
	)
	(wire
		(pts
			(xy 345.44 241.3) (xy 346.71 241.3)
		)
		(stroke
			(width 0)
			(type default)
		)
	)
	(bus
		(pts
			(xy 312.42 130.81) (xy 314.96 130.81)
		)
		(stroke
			(width 0)
			(type default)
		)
	)
	(bus
		(pts
			(xy 128.27 77.47) (xy 128.27 80.01)
		)
		(stroke
			(width 0)
			(type default)
		)
	)
	(bus
		(pts
			(xy 316.23 74.93) (xy 316.23 77.47)
		)
		(stroke
			(width 0)
			(type default)
		)
	)
	(bus
		(pts
			(xy 128.27 82.55) (xy 128.27 85.09)
		)
		(stroke
			(width 0)
			(type default)
		)
	)
	(wire
		(pts
			(xy 317.5 81.28) (xy 345.44 81.28)
		)
		(stroke
			(width 0)
			(type default)
		)
	)
	(wire
		(pts
			(xy 233.68 125.73) (xy 243.84 125.73)
		)
		(stroke
			(width 0)
			(type default)
		)
	)
	(wire
		(pts
			(xy 41.91 139.7) (xy 52.07 139.7)
		)
		(stroke
			(width 0)
			(type default)
		)
	)
	(wire
		(pts
			(xy 317.5 180.34) (xy 345.44 180.34)
		)
		(stroke
			(width 0)
			(type default)
		)
	)
	(wire
		(pts
			(xy 83.82 243.84) (xy 83.82 242.57)
		)
		(stroke
			(width 0)
			(type default)
		)
	)
	(wire
		(pts
			(xy 114.3 242.57) (xy 114.3 243.84)
		)
		(stroke
			(width 0)
			(type default)
		)
	)
	(wire
		(pts
			(xy 76.2 29.21) (xy 95.25 29.21)
		)
		(stroke
			(width 0)
			(type default)
		)
	)
	(wire
		(pts
			(xy 233.68 138.43) (xy 243.84 138.43)
		)
		(stroke
			(width 0)
			(type default)
		)
	)
	(wire
		(pts
			(xy 233.68 74.93) (xy 243.84 74.93)
		)
		(stroke
			(width 0)
			(type default)
		)
	)
	(wire
		(pts
			(xy 314.96 109.22) (xy 345.44 109.22)
		)
		(stroke
			(width 0)
			(type default)
		)
	)
	(bus
		(pts
			(xy 128.27 179.07) (xy 128.27 181.61)
		)
		(stroke
			(width 0)
			(type default)
		)
	)
	(bus
		(pts
			(xy 128.27 95.25) (xy 128.27 97.79)
		)
		(stroke
			(width 0)
			(type default)
		)
	)
	(wire
		(pts
			(xy 233.68 62.23) (xy 243.84 62.23)
		)
		(stroke
			(width 0)
			(type default)
		)
	)
	(bus
		(pts
			(xy 120.65 46.99) (xy 127 46.99)
		)
		(stroke
			(width 0)
			(type default)
		)
	)
	(bus
		(pts
			(xy 231.14 181.61) (xy 231.14 184.15)
		)
		(stroke
			(width 0)
			(type default)
		)
	)
	(bus
		(pts
			(xy 39.37 160.02) (xy 39.37 162.56)
		)
		(stroke
			(width 0)
			(type default)
		)
	)
	(wire
		(pts
			(xy 130.81 113.03) (xy 148.59 113.03)
		)
		(stroke
			(width 0)
			(type default)
		)
	)
	(wire
		(pts
			(xy 240.03 240.03) (xy 240.03 242.57)
		)
		(stroke
			(width 0)
			(type default)
		)
	)
	(wire
		(pts
			(xy 154.94 242.57) (xy 154.94 243.84)
		)
		(stroke
			(width 0)
			(type default)
		)
	)
	(wire
		(pts
			(xy 130.81 173.99) (xy 148.59 173.99)
		)
		(stroke
			(width 0)
			(type default)
		)
	)
	(wire
		(pts
			(xy 130.81 72.39) (xy 148.59 72.39)
		)
		(stroke
			(width 0)
			(type default)
		)
	)
	(bus
		(pts
			(xy 73.66 31.75) (xy 73.66 34.29)
		)
		(stroke
			(width 0)
			(type default)
		)
	)
	(bus
		(pts
			(xy 39.37 170.18) (xy 39.37 172.72)
		)
		(stroke
			(width 0)
			(type default)
		)
	)
	(bus
		(pts
			(xy 231.14 90.17) (xy 231.14 92.71)
		)
		(stroke
			(width 0)
			(type default)
		)
	)
	(wire
		(pts
			(xy 130.81 135.89) (xy 148.59 135.89)
		)
		(stroke
			(width 0)
			(type default)
		)
	)
	(wire
		(pts
			(xy 114.3 248.92) (xy 114.3 250.19)
		)
		(stroke
			(width 0)
			(type default)
		)
	)
	(wire
		(pts
			(xy 41.91 177.8) (xy 52.07 177.8)
		)
		(stroke
			(width 0)
			(type default)
		)
	)
	(bus
		(pts
			(xy 231.14 168.91) (xy 231.14 171.45)
		)
		(stroke
			(width 0)
			(type default)
		)
	)
	(bus
		(pts
			(xy 231.14 107.95) (xy 231.14 110.49)
		)
		(stroke
			(width 0)
			(type default)
		)
	)
	(bus
		(pts
			(xy 231.14 133.35) (xy 231.14 135.89)
		)
		(stroke
			(width 0)
			(type default)
		)
	)
	(bus
		(pts
			(xy 66.04 16.51) (xy 72.39 16.51)
		)
		(stroke
			(width 0)
			(type default)
		)
	)
	(wire
		(pts
			(xy 41.91 81.28) (xy 52.07 81.28)
		)
		(stroke
			(width 0)
			(type default)
		)
	)
	(wire
		(pts
			(xy 41.91 53.34) (xy 52.07 53.34)
		)
		(stroke
			(width 0)
			(type default)
		)
	)
	(wire
		(pts
			(xy 317.5 147.32) (xy 345.44 147.32)
		)
		(stroke
			(width 0)
			(type default)
		)
	)
	(bus
		(pts
			(xy 128.27 120.65) (xy 128.27 123.19)
		)
		(stroke
			(width 0)
			(type default)
		)
	)
	(wire
		(pts
			(xy 236.22 240.03) (xy 240.03 240.03)
		)
		(stroke
			(width 0)
			(type default)
		)
	)
	(wire
		(pts
			(xy 41.91 152.4) (xy 52.07 152.4)
		)
		(stroke
			(width 0)
			(type default)
		)
	)
	(bus
		(pts
			(xy 39.37 99.06) (xy 39.37 101.6)
		)
		(stroke
			(width 0)
			(type default)
		)
	)
	(bus
		(pts
			(xy 39.37 127) (xy 39.37 129.54)
		)
		(stroke
			(width 0)
			(type default)
		)
	)
	(wire
		(pts
			(xy 130.81 168.91) (xy 148.59 168.91)
		)
		(stroke
			(width 0)
			(type default)
		)
	)
	(bus
		(pts
			(xy 128.27 143.51) (xy 128.27 146.05)
		)
		(stroke
			(width 0)
			(type default)
		)
	)
	(bus
		(pts
			(xy 39.37 114.3) (xy 39.37 116.84)
		)
		(stroke
			(width 0)
			(type default)
		)
	)
	(bus
		(pts
			(xy 73.66 21.59) (xy 73.66 24.13)
		)
		(stroke
			(width 0)
			(type default)
		)
	)
	(wire
		(pts
			(xy 130.81 171.45) (xy 148.59 171.45)
		)
		(stroke
			(width 0)
			(type default)
		)
	)
	(wire
		(pts
			(xy 41.91 124.46) (xy 52.07 124.46)
		)
		(stroke
			(width 0)
			(type default)
		)
	)
	(wire
		(pts
			(xy 317.5 66.04) (xy 345.44 66.04)
		)
		(stroke
			(width 0)
			(type default)
		)
	)
	(bus
		(pts
			(xy 311.15 86.36) (xy 312.42 87.63)
		)
		(stroke
			(width 0)
			(type default)
		)
	)
	(wire
		(pts
			(xy 41.91 116.84) (xy 52.07 116.84)
		)
		(stroke
			(width 0)
			(type default)
		)
	)
	(bus
		(pts
			(xy 312.42 96.52) (xy 312.42 99.06)
		)
		(stroke
			(width 0)
			(type default)
		)
	)
	(wire
		(pts
			(xy 233.68 130.81) (xy 243.84 130.81)
		)
		(stroke
			(width 0)
			(type default)
		)
	)
	(wire
		(pts
			(xy 335.28 53.34) (xy 345.44 53.34)
		)
		(stroke
			(width 0)
			(type default)
		)
	)
	(wire
		(pts
			(xy 233.68 135.89) (xy 243.84 135.89)
		)
		(stroke
			(width 0)
			(type default)
		)
	)
	(wire
		(pts
			(xy 124.46 243.84) (xy 124.46 242.57)
		)
		(stroke
			(width 0)
			(type default)
		)
	)
	(wire
		(pts
			(xy 233.68 87.63) (xy 243.84 87.63)
		)
		(stroke
			(width 0)
			(type default)
		)
	)
	(wire
		(pts
			(xy 130.81 115.57) (xy 148.59 115.57)
		)
		(stroke
			(width 0)
			(type default)
		)
	)
	(bus
		(pts
			(xy 128.27 69.85) (xy 128.27 72.39)
		)
		(stroke
			(width 0)
			(type default)
		)
	)
	(bus
		(pts
			(xy 128.27 110.49) (xy 128.27 113.03)
		)
		(stroke
			(width 0)
			(type default)
		)
	)
	(wire
		(pts
			(xy 130.81 143.51) (xy 148.59 143.51)
		)
		(stroke
			(width 0)
			(type default)
		)
	)
	(wire
		(pts
			(xy 41.91 142.24) (xy 52.07 142.24)
		)
		(stroke
			(width 0)
			(type default)
		)
	)
	(wire
		(pts
			(xy 130.81 90.17) (xy 148.59 90.17)
		)
		(stroke
			(width 0)
			(type default)
		)
	)
	(wire
		(pts
			(xy 148.59 156.21) (xy 130.81 156.21)
		)
		(stroke
			(width 0)
			(type default)
		)
	)
	(wire
		(pts
			(xy 325.12 119.38) (xy 345.44 119.38)
		)
		(stroke
			(width 0)
			(type default)
		)
	)
	(wire
		(pts
			(xy 93.98 242.57) (xy 93.98 243.84)
		)
		(stroke
			(width 0)
			(type default)
		)
	)
	(wire
		(pts
			(xy 233.68 171.45) (xy 243.84 171.45)
		)
		(stroke
			(width 0)
			(type default)
		)
	)
	(wire
		(pts
			(xy 130.81 130.81) (xy 148.59 130.81)
		)
		(stroke
			(width 0)
			(type default)
		)
	)
	(wire
		(pts
			(xy 317.5 63.5) (xy 345.44 63.5)
		)
		(stroke
			(width 0)
			(type default)
		)
	)
	(wire
		(pts
			(xy 130.81 163.83) (xy 148.59 163.83)
		)
		(stroke
			(width 0)
			(type default)
		)
	)
	(wire
		(pts
			(xy 233.68 166.37) (xy 243.84 166.37)
		)
		(stroke
			(width 0)
			(type default)
		)
	)
	(wire
		(pts
			(xy 41.91 101.6) (xy 52.07 101.6)
		)
		(stroke
			(width 0)
			(type default)
		)
	)
	(bus
		(pts
			(xy 128.27 100.33) (xy 128.27 102.87)
		)
		(stroke
			(width 0)
			(type default)
		)
	)
	(bus
		(pts
			(xy 231.14 171.45) (xy 231.14 173.99)
		)
		(stroke
			(width 0)
			(type default)
		)
	)
	(bus
		(pts
			(xy 128.27 85.09) (xy 128.27 90.17)
		)
		(stroke
			(width 0)
			(type default)
		)
	)
	(wire
		(pts
			(xy 325.12 116.84) (xy 345.44 116.84)
		)
		(stroke
			(width 0)
			(type default)
		)
	)
	(bus
		(pts
			(xy 231.14 72.39) (xy 231.14 74.93)
		)
		(stroke
			(width 0)
			(type default)
		)
	)
	(wire
		(pts
			(xy 317.5 68.58) (xy 345.44 68.58)
		)
		(stroke
			(width 0)
			(type default)
		)
	)
	(bus
		(pts
			(xy 231.14 179.07) (xy 231.14 181.61)
		)
		(stroke
			(width 0)
			(type default)
		)
	)
	(wire
		(pts
			(xy 314.96 93.98) (xy 345.44 93.98)
		)
		(stroke
			(width 0)
			(type default)
		)
	)
	(polyline
		(pts
			(xy 186.055 201.93) (xy 186.055 283.845)
		)
		(stroke
			(width 0)
			(type default)
		)
	)
	(wire
		(pts
			(xy 317.5 175.26) (xy 345.44 175.26)
		)
		(stroke
			(width 0)
			(type default)
		)
	)
	(wire
		(pts
			(xy 81.28 234.95) (xy 83.82 234.95)
		)
		(stroke
			(width 0)
			(type default)
		)
	)
	(bus
		(pts
			(xy 31.75 45.72) (xy 38.1 45.72)
		)
		(stroke
			(width 0)
			(type default)
		)
	)
	(bus
		(pts
			(xy 38.1 45.72) (xy 39.37 46.99)
		)
		(stroke
			(width 0)
			(type default)
		)
	)
	(bus
		(pts
			(xy 316.23 80.01) (xy 316.23 82.55)
		)
		(stroke
			(width 0)
			(type default)
		)
	)
	(wire
		(pts
			(xy 233.68 85.09) (xy 243.84 85.09)
		)
		(stroke
			(width 0)
			(type default)
		)
	)
	(bus
		(pts
			(xy 39.37 116.84) (xy 39.37 121.92)
		)
		(stroke
			(width 0)
			(type default)
		)
	)
	(wire
		(pts
			(xy 41.91 96.52) (xy 52.07 96.52)
		)
		(stroke
			(width 0)
			(type default)
		)
	)
	(bus
		(pts
			(xy 231.14 102.87) (xy 231.14 105.41)
		)
		(stroke
			(width 0)
			(type default)
		)
	)
	(wire
		(pts
			(xy 314.96 106.68) (xy 345.44 106.68)
		)
		(stroke
			(width 0)
			(type default)
		)
	)
	(wire
		(pts
			(xy 317.5 177.8) (xy 345.44 177.8)
		)
		(stroke
			(width 0)
			(type default)
		)
	)
	(bus
		(pts
			(xy 39.37 175.26) (xy 39.37 177.8)
		)
		(stroke
			(width 0)
			(type default)
		)
	)
	(wire
		(pts
			(xy 130.81 179.07) (xy 148.59 179.07)
		)
		(stroke
			(width 0)
			(type default)
		)
	)
	(wire
		(pts
			(xy 233.68 158.75) (xy 243.84 158.75)
		)
		(stroke
			(width 0)
			(type default)
		)
	)
	(wire
		(pts
			(xy 41.91 180.34) (xy 52.07 180.34)
		)
		(stroke
			(width 0)
			(type default)
		)
	)
	(wire
		(pts
			(xy 154.94 248.92) (xy 154.94 250.19)
		)
		(stroke
			(width 0)
			(type default)
		)
	)
	(bus
		(pts
			(xy 316.23 85.09) (xy 316.23 90.17)
		)
		(stroke
			(width 0)
			(type default)
		)
	)
	(bus
		(pts
			(xy 128.27 176.53) (xy 128.27 179.07)
		)
		(stroke
			(width 0)
			(type default)
		)
	)
	(wire
		(pts
			(xy 345.44 242.57) (xy 345.44 241.3)
		)
		(stroke
			(width 0)
			(type default)
		)
	)
	(wire
		(pts
			(xy 130.81 181.61) (xy 148.59 181.61)
		)
		(stroke
			(width 0)
			(type default)
		)
	)
	(bus
		(pts
			(xy 316.23 59.69) (xy 316.23 62.23)
		)
		(stroke
			(width 0)
			(type default)
		)
	)
	(wire
		(pts
			(xy 325.12 129.54) (xy 345.44 129.54)
		)
		(stroke
			(width 0)
			(type default)
		)
	)
	(wire
		(pts
			(xy 130.81 125.73) (xy 148.59 125.73)
		)
		(stroke
			(width 0)
			(type default)
		)
	)
	(bus
		(pts
			(xy 39.37 91.44) (xy 39.37 93.98)
		)
		(stroke
			(width 0)
			(type default)
		)
	)
	(bus
		(pts
			(xy 39.37 55.88) (xy 39.37 58.42)
		)
		(stroke
			(width 0)
			(type default)
		)
	)
	(bus
		(pts
			(xy 231.14 163.83) (xy 231.14 166.37)
		)
		(stroke
			(width 0)
			(type default)
		)
	)
	(wire
		(pts
			(xy 317.5 165.1) (xy 345.44 165.1)
		)
		(stroke
			(width 0)
			(type default)
		)
	)
	(bus
		(pts
			(xy 316.23 173.99) (xy 316.23 176.53)
		)
		(stroke
			(width 0)
			(type default)
		)
	)
	(wire
		(pts
			(xy 83.82 227.33) (xy 83.82 234.95)
		)
		(stroke
			(width 0)
			(type default)
		)
	)
	(bus
		(pts
			(xy 128.27 48.26) (xy 128.27 57.15)
		)
		(stroke
			(width 0)
			(type default)
		)
	)
	(wire
		(pts
			(xy 41.91 129.54) (xy 52.07 129.54)
		)
		(stroke
			(width 0)
			(type default)
		)
	)
	(bus
		(pts
			(xy 231.14 118.11) (xy 231.14 123.19)
		)
		(stroke
			(width 0)
			(type default)
		)
	)
	(bus
		(pts
			(xy 128.27 158.75) (xy 128.27 161.29)
		)
		(stroke
			(width 0)
			(type default)
		)
	)
	(bus
		(pts
			(xy 128.27 72.39) (xy 128.27 74.93)
		)
		(stroke
			(width 0)
			(type default)
		)
	)
	(wire
		(pts
			(xy 233.68 168.91) (xy 243.84 168.91)
		)
		(stroke
			(width 0)
			(type default)
		)
	)
	(bus
		(pts
			(xy 316.23 57.15) (xy 316.23 59.69)
		)
		(stroke
			(width 0)
			(type default)
		)
	)
	(bus
		(pts
			(xy 231.14 97.79) (xy 231.14 100.33)
		)
		(stroke
			(width 0)
			(type default)
		)
	)
	(wire
		(pts
			(xy 317.5 170.18) (xy 345.44 170.18)
		)
		(stroke
			(width 0)
			(type default)
		)
	)
	(wire
		(pts
			(xy 233.68 161.29) (xy 243.84 161.29)
		)
		(stroke
			(width 0)
			(type default)
		)
	)
	(bus
		(pts
			(xy 128.27 57.15) (xy 128.27 59.69)
		)
		(stroke
			(width 0)
			(type default)
		)
	)
	(bus
		(pts
			(xy 128.27 166.37) (xy 128.27 168.91)
		)
		(stroke
			(width 0)
			(type default)
		)
	)
	(wire
		(pts
			(xy 130.81 158.75) (xy 148.59 158.75)
		)
		(stroke
			(width 0)
			(type default)
		)
	)
	(bus
		(pts
			(xy 312.42 91.44) (xy 312.42 93.98)
		)
		(stroke
			(width 0)
			(type default)
		)
	)
	(bus
		(pts
			(xy 128.27 92.71) (xy 128.27 95.25)
		)
		(stroke
			(width 0)
			(type default)
		)
	)
	(wire
		(pts
			(xy 41.91 144.78) (xy 52.07 144.78)
		)
		(stroke
			(width 0)
			(type default)
		)
	)
	(wire
		(pts
			(xy 233.68 181.61) (xy 243.84 181.61)
		)
		(stroke
			(width 0)
			(type default)
		)
	)
	(wire
		(pts
			(xy 233.68 133.35) (xy 243.84 133.35)
		)
		(stroke
			(width 0)
			(type default)
		)
	)
	(wire
		(pts
			(xy 104.14 242.57) (xy 114.3 242.57)
		)
		(stroke
			(width 0)
			(type default)
		)
	)
	(bus
		(pts
			(xy 128.27 173.99) (xy 128.27 176.53)
		)
		(stroke
			(width 0)
			(type default)
		)
	)
	(wire
		(pts
			(xy 130.81 118.11) (xy 148.59 118.11)
		)
		(stroke
			(width 0)
			(type default)
		)
	)
	(wire
		(pts
			(xy 130.81 95.25) (xy 148.59 95.25)
		)
		(stroke
			(width 0)
			(type default)
		)
	)
	(bus
		(pts
			(xy 39.37 106.68) (xy 39.37 109.22)
		)
		(stroke
			(width 0)
			(type default)
		)
	)
	(wire
		(pts
			(xy 314.96 96.52) (xy 345.44 96.52)
		)
		(stroke
			(width 0)
			(type default)
		)
	)
	(bus
		(pts
			(xy 128.27 133.35) (xy 128.27 135.89)
		)
		(stroke
			(width 0)
			(type default)
		)
	)
	(wire
		(pts
			(xy 233.68 67.31) (xy 243.84 67.31)
		)
		(stroke
			(width 0)
			(type default)
		)
	)
	(wire
		(pts
			(xy 130.81 67.31) (xy 148.59 67.31)
		)
		(stroke
			(width 0)
			(type default)
		)
	)
	(bus
		(pts
			(xy 39.37 165.1) (xy 39.37 167.64)
		)
		(stroke
			(width 0)
			(type default)
		)
	)
	(wire
		(pts
			(xy 134.62 234.95) (xy 134.62 236.22)
		)
		(stroke
			(width 0)
			(type default)
		)
	)
	(wire
		(pts
			(xy 317.5 71.12) (xy 345.44 71.12)
		)
		(stroke
			(width 0)
			(type default)
		)
	)
	(wire
		(pts
			(xy 41.91 162.56) (xy 52.07 162.56)
		)
		(stroke
			(width 0)
			(type default)
		)
	)
	(wire
		(pts
			(xy 233.68 118.11) (xy 243.84 118.11)
		)
		(stroke
			(width 0)
			(type default)
		)
	)
	(bus
		(pts
			(xy 128.27 130.81) (xy 128.27 133.35)
		)
		(stroke
			(width 0)
			(type default)
		)
	)
	(wire
		(pts
			(xy 41.91 58.42) (xy 52.07 58.42)
		)
		(stroke
			(width 0)
			(type default)
		)
	)
	(bus
		(pts
			(xy 128.27 146.05) (xy 128.27 148.59)
		)
		(stroke
			(width 0)
			(type default)
		)
	)
	(bus
		(pts
			(xy 39.37 157.48) (xy 39.37 160.02)
		)
		(stroke
			(width 0)
			(type default)
		)
	)
	(bus
		(pts
			(xy 231.14 161.29) (xy 231.14 163.83)
		)
		(stroke
			(width 0)
			(type default)
		)
	)
	(bus
		(pts
			(xy 39.37 104.14) (xy 39.37 106.68)
		)
		(stroke
			(width 0)
			(type default)
		)
	)
	(wire
		(pts
			(xy 233.68 115.57) (xy 243.84 115.57)
		)
		(stroke
			(width 0)
			(type default)
		)
	)
	(bus
		(pts
			(xy 312.42 104.14) (xy 312.42 106.68)
		)
		(stroke
			(width 0)
			(type default)
		)
	)
	(bus
		(pts
			(xy 39.37 63.5) (xy 39.37 66.04)
		)
		(stroke
			(width 0)
			(type default)
		)
	)
	(bus
		(pts
			(xy 128.27 80.01) (xy 128.27 82.55)
		)
		(stroke
			(width 0)
			(type default)
		)
	)
	(wire
		(pts
			(xy 260.35 257.81) (xy 260.35 260.35)
		)
		(stroke
			(width 0)
			(type default)
		)
	)
	(bus
		(pts
			(xy 39.37 101.6) (xy 39.37 104.14)
		)
		(stroke
			(width 0)
			(type default)
		)
	)
	(bus
		(pts
			(xy 231.14 128.27) (xy 231.14 130.81)
		)
		(stroke
			(width 0)
			(type default)
		)
	)
	(bus
		(pts
			(xy 316.23 55.88) (xy 316.23 57.15)
		)
		(stroke
			(width 0)
			(type default)
		)
	)
	(wire
		(pts
			(xy 46.99 234.95) (xy 76.2 234.95)
		)
		(stroke
			(width 0)
			(type default)
		)
	)
	(wire
		(pts
			(xy 130.81 102.87) (xy 148.59 102.87)
		)
		(stroke
			(width 0)
			(type default)
		)
	)
	(wire
		(pts
			(xy 41.91 167.64) (xy 52.07 167.64)
		)
		(stroke
			(width 0)
			(type default)
		)
	)
	(wire
		(pts
			(xy 41.91 147.32) (xy 52.07 147.32)
		)
		(stroke
			(width 0)
			(type default)
		)
	)
	(bus
		(pts
			(xy 39.37 144.78) (xy 39.37 147.32)
		)
		(stroke
			(width 0)
			(type default)
		)
	)
	(wire
		(pts
			(xy 130.81 92.71) (xy 148.59 92.71)
		)
		(stroke
			(width 0)
			(type default)
		)
	)
	(bus
		(pts
			(xy 39.37 124.46) (xy 39.37 127)
		)
		(stroke
			(width 0)
			(type default)
		)
	)
	(wire
		(pts
			(xy 76.2 36.83) (xy 95.25 36.83)
		)
		(stroke
			(width 0)
			(type default)
		)
	)
	(bus
		(pts
			(xy 73.66 26.67) (xy 73.66 29.21)
		)
		(stroke
			(width 0)
			(type default)
		)
	)
	(wire
		(pts
			(xy 317.5 162.56) (xy 345.44 162.56)
		)
		(stroke
			(width 0)
			(type default)
		)
	)
	(bus
		(pts
			(xy 316.23 163.83) (xy 316.23 166.37)
		)
		(stroke
			(width 0)
			(type default)
		)
	)
	(bus
		(pts
			(xy 231.14 148.59) (xy 231.14 151.13)
		)
		(stroke
			(width 0)
			(type default)
		)
	)
	(bus
		(pts
			(xy 316.23 148.59) (xy 316.23 151.13)
		)
		(stroke
			(width 0)
			(type default)
		)
	)
	(wire
		(pts
			(xy 233.68 151.13) (xy 243.84 151.13)
		)
		(stroke
			(width 0)
			(type default)
		)
	)
	(bus
		(pts
			(xy 39.37 78.74) (xy 39.37 81.28)
		)
		(stroke
			(width 0)
			(type default)
		)
	)
	(wire
		(pts
			(xy 335.28 231.14) (xy 335.28 232.41)
		)
		(stroke
			(width 0)
			(type default)
		)
	)
	(bus
		(pts
			(xy 39.37 109.22) (xy 39.37 111.76)
		)
		(stroke
			(width 0)
			(type default)
		)
	)
	(bus
		(pts
			(xy 316.23 143.51) (xy 316.23 146.05)
		)
		(stroke
			(width 0)
			(type default)
		)
	)
	(bus
		(pts
			(xy 223.52 44.45) (xy 229.87 44.45)
		)
		(stroke
			(width 0)
			(type default)
		)
	)
	(bus
		(pts
			(xy 39.37 147.32) (xy 39.37 149.86)
		)
		(stroke
			(width 0)
			(type default)
		)
	)
	(bus
		(pts
			(xy 127 119.38) (xy 128.27 120.65)
		)
		(stroke
			(width 0)
			(type default)
		)
	)
	(wire
		(pts
			(xy 124.46 242.57) (xy 134.62 242.57)
		)
		(stroke
			(width 0)
			(type default)
		)
	)
	(bus
		(pts
			(xy 316.23 64.77) (xy 316.23 67.31)
		)
		(stroke
			(width 0)
			(type default)
		)
	)
	(wire
		(pts
			(xy 240.03 257.81) (xy 240.03 260.35)
		)
		(stroke
			(width 0)
			(type default)
		)
	)
	(wire
		(pts
			(xy 314.96 104.14) (xy 345.44 104.14)
		)
		(stroke
			(width 0)
			(type default)
		)
	)
	(bus
		(pts
			(xy 128.27 123.19) (xy 128.27 125.73)
		)
		(stroke
			(width 0)
			(type default)
		)
	)
	(wire
		(pts
			(xy 346.71 238.76) (xy 345.44 238.76)
		)
		(stroke
			(width 0)
			(type default)
		)
	)
	(wire
		(pts
			(xy 222.25 240.03) (xy 231.14 240.03)
		)
		(stroke
			(width 0)
			(type default)
		)
	)
	(wire
		(pts
			(xy 233.68 184.15) (xy 243.84 184.15)
		)
		(stroke
			(width 0)
			(type default)
		)
	)
	(bus
		(pts
			(xy 39.37 66.04) (xy 39.37 68.58)
		)
		(stroke
			(width 0)
			(type default)
		)
	)
	(bus
		(pts
			(xy 308.61 86.36) (xy 311.15 86.36)
		)
		(stroke
			(width 0)
			(type default)
		)
	)
	(wire
		(pts
			(xy 317.5 60.96) (xy 345.44 60.96)
		)
		(stroke
			(width 0)
			(type default)
		)
	)
	(wire
		(pts
			(xy 233.68 110.49) (xy 243.84 110.49)
		)
		(stroke
			(width 0)
			(type default)
		)
	)
	(bus
		(pts
			(xy 231.14 92.71) (xy 231.14 95.25)
		)
		(stroke
			(width 0)
			(type default)
		)
	)
	(wire
		(pts
			(xy 93.98 248.92) (xy 93.98 250.19)
		)
		(stroke
			(width 0)
			(type default)
		)
	)
	(wire
		(pts
			(xy 129.54 189.23) (xy 148.59 189.23)
		)
		(stroke
			(width 0)
			(type default)
		)
	)
	(wire
		(pts
			(xy 73.66 227.33) (xy 76.2 227.33)
		)
		(stroke
			(width 0)
			(type default)
		)
	)
	(bus
		(pts
			(xy 39.37 73.66) (xy 39.37 76.2)
		)
		(stroke
			(width 0)
			(type default)
		)
	)
	(wire
		(pts
			(xy 74.93 39.37) (xy 95.25 39.37)
		)
		(stroke
			(width 0)
			(type default)
		)
	)
	(bus
		(pts
			(xy 128.27 181.61) (xy 128.27 184.15)
		)
		(stroke
			(width 0)
			(type default)
		)
	)
	(bus
		(pts
			(xy 128.27 148.59) (xy 128.27 151.13)
		)
		(stroke
			(width 0)
			(type default)
		)
	)
	(bus
		(pts
			(xy 231.14 69.85) (xy 231.14 72.39)
		)
		(stroke
			(width 0)
			(type default)
		)
	)
	(wire
		(pts
			(xy 130.81 59.69) (xy 148.59 59.69)
		)
		(stroke
			(width 0)
			(type default)
		)
	)
	(bus
		(pts
			(xy 39.37 93.98) (xy 39.37 96.52)
		)
		(stroke
			(width 0)
			(type default)
		)
	)
	(bus
		(pts
			(xy 231.14 123.19) (xy 231.14 125.73)
		)
		(stroke
			(width 0)
			(type default)
		)
	)
	(bus
		(pts
			(xy 128.27 62.23) (xy 128.27 64.77)
		)
		(stroke
			(width 0)
			(type default)
		)
	)
	(bus
		(pts
			(xy 229.87 44.45) (xy 231.14 45.72)
		)
		(stroke
			(width 0)
			(type default)
		)
	)
	(wire
		(pts
			(xy 317.5 142.24) (xy 345.44 142.24)
		)
		(stroke
			(width 0)
			(type default)
		)
	)
	(wire
		(pts
			(xy 130.81 74.93) (xy 148.59 74.93)
		)
		(stroke
			(width 0)
			(type default)
		)
	)
	(wire
		(pts
			(xy 41.91 106.68) (xy 52.07 106.68)
		)
		(stroke
			(width 0)
			(type default)
		)
	)
	(bus
		(pts
			(xy 39.37 81.28) (xy 39.37 83.82)
		)
		(stroke
			(width 0)
			(type default)
		)
	)
	(wire
		(pts
			(xy 41.91 83.82) (xy 52.07 83.82)
		)
		(stroke
			(width 0)
			(type default)
		)
	)
	(wire
		(pts
			(xy 114.3 241.3) (xy 114.3 242.57)
		)
		(stroke
			(width 0)
			(type default)
		)
	)
	(bus
		(pts
			(xy 128.27 90.17) (xy 128.27 92.71)
		)
		(stroke
			(width 0)
			(type default)
		)
	)
	(wire
		(pts
			(xy 41.91 172.72) (xy 52.07 172.72)
		)
		(stroke
			(width 0)
			(type default)
		)
	)
	(bus
		(pts
			(xy 231.14 130.81) (xy 231.14 133.35)
		)
		(stroke
			(width 0)
			(type default)
		)
	)
	(wire
		(pts
			(xy 130.81 133.35) (xy 148.59 133.35)
		)
		(stroke
			(width 0)
			(type default)
		)
	)
	(wire
		(pts
			(xy 93.98 234.95) (xy 93.98 236.22)
		)
		(stroke
			(width 0)
			(type default)
		)
	)
	(wire
		(pts
			(xy 223.52 257.81) (xy 231.14 257.81)
		)
		(stroke
			(width 0)
			(type default)
		)
	)
	(bus
		(pts
			(xy 39.37 134.62) (xy 39.37 137.16)
		)
		(stroke
			(width 0)
			(type default)
		)
	)
	(wire
		(pts
			(xy 317.5 134.62) (xy 345.44 134.62)
		)
		(stroke
			(width 0)
			(type default)
		)
	)
	(bus
		(pts
			(xy 312.42 101.6) (xy 312.42 104.14)
		)
		(stroke
			(width 0)
			(type default)
		)
	)
	(bus
		(pts
			(xy 231.14 59.69) (xy 231.14 62.23)
		)
		(stroke
			(width 0)
			(type default)
		)
	)
	(wire
		(pts
			(xy 314.96 101.6) (xy 345.44 101.6)
		)
		(stroke
			(width 0)
			(type default)
		)
	)
	(wire
		(pts
			(xy 233.68 107.95) (xy 243.84 107.95)
		)
		(stroke
			(width 0)
			(type default)
		)
	)
	(wire
		(pts
			(xy 41.91 165.1) (xy 52.07 165.1)
		)
		(stroke
			(width 0)
			(type default)
		)
	)
	(bus
		(pts
			(xy 39.37 76.2) (xy 39.37 78.74)
		)
		(stroke
			(width 0)
			(type default)
		)
	)
	(bus
		(pts
			(xy 39.37 139.7) (xy 39.37 142.24)
		)
		(stroke
			(width 0)
			(type default)
		)
	)
	(bus
		(pts
			(xy 128.27 74.93) (xy 128.27 77.47)
		)
		(stroke
			(width 0)
			(type default)
		)
	)
	(bus
		(pts
			(xy 39.37 154.94) (xy 39.37 157.48)
		)
		(stroke
			(width 0)
			(type default)
		)
	)
	(bus
		(pts
			(xy 316.23 171.45) (xy 316.23 173.99)
		)
		(stroke
			(width 0)
			(type default)
		)
	)
	(wire
		(pts
			(xy 317.5 137.16) (xy 345.44 137.16)
		)
		(stroke
			(width 0)
			(type default)
		)
	)
	(bus
		(pts
			(xy 231.14 146.05) (xy 231.14 148.59)
		)
		(stroke
			(width 0)
			(type default)
		)
	)
	(wire
		(pts
			(xy 256.54 257.81) (xy 260.35 257.81)
		)
		(stroke
			(width 0)
			(type default)
		)
	)
	(bus
		(pts
			(xy 312.42 99.06) (xy 312.42 101.6)
		)
		(stroke
			(width 0)
			(type default)
		)
	)
	(wire
		(pts
			(xy 41.91 134.62) (xy 52.07 134.62)
		)
		(stroke
			(width 0)
			(type default)
		)
	)
	(bus
		(pts
			(xy 231.14 151.13) (xy 231.14 156.21)
		)
		(stroke
			(width 0)
			(type default)
		)
	)
	(wire
		(pts
			(xy 130.81 176.53) (xy 148.59 176.53)
		)
		(stroke
			(width 0)
			(type default)
		)
	)
	(bus
		(pts
			(xy 120.65 119.38) (xy 127 119.38)
		)
		(stroke
			(width 0)
			(type default)
		)
	)
	(wire
		(pts
			(xy 233.68 90.17) (xy 243.84 90.17)
		)
		(stroke
			(width 0)
			(type default)
		)
	)
	(wire
		(pts
			(xy 233.68 92.71) (xy 243.84 92.71)
		)
		(stroke
			(width 0)
			(type default)
		)
	)
	(wire
		(pts
			(xy 233.68 173.99) (xy 243.84 173.99)
		)
		(stroke
			(width 0)
			(type default)
		)
	)
	(wire
		(pts
			(xy 134.62 241.3) (xy 134.62 242.57)
		)
		(stroke
			(width 0)
			(type default)
		)
	)
	(bus
		(pts
			(xy 128.27 151.13) (xy 128.27 156.21)
		)
		(stroke
			(width 0)
			(type default)
		)
	)
	(wire
		(pts
			(xy 41.91 157.48) (xy 52.07 157.48)
		)
		(stroke
			(width 0)
			(type default)
		)
	)
	(wire
		(pts
			(xy 233.68 163.83) (xy 243.84 163.83)
		)
		(stroke
			(width 0)
			(type default)
		)
	)
	(bus
		(pts
			(xy 128.27 64.77) (xy 128.27 67.31)
		)
		(stroke
			(width 0)
			(type default)
		)
	)
	(wire
		(pts
			(xy 83.82 234.95) (xy 93.98 234.95)
		)
		(stroke
			(width 0)
			(type default)
		)
	)
	(bus
		(pts
			(xy 39.37 121.92) (xy 39.37 124.46)
		)
		(stroke
			(width 0)
			(type default)
		)
	)
	(wire
		(pts
			(xy 41.91 182.88) (xy 52.07 182.88)
		)
		(stroke
			(width 0)
			(type default)
		)
	)
	(bus
		(pts
			(xy 316.23 69.85) (xy 316.23 72.39)
		)
		(stroke
			(width 0)
			(type default)
		)
	)
	(wire
		(pts
			(xy 325.12 132.08) (xy 345.44 132.08)
		)
		(stroke
			(width 0)
			(type default)
		)
	)
	(bus
		(pts
			(xy 231.14 138.43) (xy 231.14 140.97)
		)
		(stroke
			(width 0)
			(type default)
		)
	)
	(wire
		(pts
			(xy 130.81 85.09) (xy 148.59 85.09)
		)
		(stroke
			(width 0)
			(type default)
		)
	)
	(wire
		(pts
			(xy 76.2 31.75) (xy 95.25 31.75)
		)
		(stroke
			(width 0)
			(type default)
		)
	)
	(bus
		(pts
			(xy 128.27 102.87) (xy 128.27 110.49)
		)
		(stroke
			(width 0)
			(type default)
		)
	)
	(bus
		(pts
			(xy 316.23 146.05) (xy 316.23 148.59)
		)
		(stroke
			(width 0)
			(type default)
		)
	)
	(wire
		(pts
			(xy 130.81 110.49) (xy 148.59 110.49)
		)
		(stroke
			(width 0)
			(type default)
		)
	)
	(bus
		(pts
			(xy 231.14 166.37) (xy 231.14 168.91)
		)
		(stroke
			(width 0)
			(type default)
		)
	)
	(bus
		(pts
			(xy 231.14 67.31) (xy 231.14 69.85)
		)
		(stroke
			(width 0)
			(type default)
		)
	)
	(bus
		(pts
			(xy 231.14 95.25) (xy 231.14 97.79)
		)
		(stroke
			(width 0)
			(type default)
		)
	)
	(bus
		(pts
			(xy 128.27 115.57) (xy 128.27 118.11)
		)
		(stroke
			(width 0)
			(type default)
		)
	)
	(wire
		(pts
			(xy 345.44 236.22) (xy 345.44 238.76)
		)
		(stroke
			(width 0)
			(type default)
		)
	)
	(wire
		(pts
			(xy 130.81 161.29) (xy 148.59 161.29)
		)
		(stroke
			(width 0)
			(type default)
		)
	)
	(bus
		(pts
			(xy 231.14 125.73) (xy 231.14 128.27)
		)
		(stroke
			(width 0)
			(type default)
		)
	)
	(bus
		(pts
			(xy 128.27 128.27) (xy 128.27 130.81)
		)
		(stroke
			(width 0)
			(type default)
		)
	)
	(bus
		(pts
			(xy 316.23 135.89) (xy 316.23 138.43)
		)
		(stroke
			(width 0)
			(type default)
		)
	)
	(wire
		(pts
			(xy 130.81 146.05) (xy 148.59 146.05)
		)
		(stroke
			(width 0)
			(type default)
		)
	)
	(wire
		(pts
			(xy 365.76 236.22) (xy 384.81 236.22)
		)
		(stroke
			(width 0)
			(type default)
		)
	)
	(bus
		(pts
			(xy 316.23 82.55) (xy 316.23 85.09)
		)
		(stroke
			(width 0)
			(type default)
		)
	)
	(bus
		(pts
			(xy 39.37 60.96) (xy 39.37 63.5)
		)
		(stroke
			(width 0)
			(type default)
		)
	)
	(wire
		(pts
			(xy 46.99 234.95) (xy 46.99 237.49)
		)
		(stroke
			(width 0)
			(type default)
		)
	)
	(wire
		(pts
			(xy 130.81 64.77) (xy 148.59 64.77)
		)
		(stroke
			(width 0)
			(type default)
		)
	)
	(bus
		(pts
			(xy 231.14 100.33) (xy 231.14 102.87)
		)
		(stroke
			(width 0)
			(type default)
		)
	)
	(wire
		(pts
			(xy 317.5 149.86) (xy 345.44 149.86)
		)
		(stroke
			(width 0)
			(type default)
		)
	)
	(wire
		(pts
			(xy 130.81 87.63) (xy 148.59 87.63)
		)
		(stroke
			(width 0)
			(type default)
		)
	)
	(bus
		(pts
			(xy 128.27 168.91) (xy 128.27 171.45)
		)
		(stroke
			(width 0)
			(type default)
		)
	)
	(wire
		(pts
			(xy 233.68 97.79) (xy 243.84 97.79)
		)
		(stroke
			(width 0)
			(type default)
		)
	)
	(wire
		(pts
			(xy 41.91 160.02) (xy 52.07 160.02)
		)
		(stroke
			(width 0)
			(type default)
		)
	)
	(wire
		(pts
			(xy 41.91 109.22) (xy 52.07 109.22)
		)
		(stroke
			(width 0)
			(type default)
		)
	)
	(wire
		(pts
			(xy 365.76 238.76) (xy 384.81 238.76)
		)
		(stroke
			(width 0)
			(type default)
		)
	)
	(bus
		(pts
			(xy 128.27 113.03) (xy 128.27 115.57)
		)
		(stroke
			(width 0)
			(type default)
		)
	)
	(wire
		(pts
			(xy 317.5 76.2) (xy 345.44 76.2)
		)
		(stroke
			(width 0)
			(type default)
		)
	)
	(wire
		(pts
			(xy 130.81 69.85) (xy 148.59 69.85)
		)
		(stroke
			(width 0)
			(type default)
		)
	)
	(wire
		(pts
			(xy 317.5 167.64) (xy 345.44 167.64)
		)
		(stroke
			(width 0)
			(type default)
		)
	)
	(bus
		(pts
			(xy 127 46.99) (xy 128.27 48.26)
		)
		(stroke
			(width 0)
			(type default)
		)
	)
	(bus
		(pts
			(xy 128.27 135.89) (xy 128.27 143.51)
		)
		(stroke
			(width 0)
			(type default)
		)
	)
	(wire
		(pts
			(xy 114.3 234.95) (xy 114.3 236.22)
		)
		(stroke
			(width 0)
			(type default)
		)
	)
	(bus
		(pts
			(xy 316.23 161.29) (xy 316.23 163.83)
		)
		(stroke
			(width 0)
			(type default)
		)
	)
	(bus
		(pts
			(xy 39.37 172.72) (xy 39.37 175.26)
		)
		(stroke
			(width 0)
			(type default)
		)
	)
	(bus
		(pts
			(xy 316.23 140.97) (xy 316.23 143.51)
		)
		(stroke
			(width 0)
			(type default)
		)
	)
	(bus
		(pts
			(xy 231.14 80.01) (xy 231.14 82.55)
		)
		(stroke
			(width 0)
			(type default)
		)
	)
	(bus
		(pts
			(xy 313.69 54.61) (xy 314.96 54.61)
		)
		(stroke
			(width 0)
			(type default)
		)
	)
	(wire
		(pts
			(xy 41.91 111.76) (xy 52.07 111.76)
		)
		(stroke
			(width 0)
			(type default)
		)
	)
	(bus
		(pts
			(xy 231.14 57.15) (xy 231.14 59.69)
		)
		(stroke
			(width 0)
			(type default)
		)
	)
	(bus
		(pts
			(xy 316.23 179.07) (xy 316.23 181.61)
		)
		(stroke
			(width 0)
			(type default)
		)
	)
	(wire
		(pts
			(xy 81.28 227.33) (xy 83.82 227.33)
		)
		(stroke
			(width 0)
			(type default)
		)
	)
	(bus
		(pts
			(xy 39.37 83.82) (xy 39.37 88.9)
		)
		(stroke
			(width 0)
			(type default)
		)
	)
	(wire
		(pts
			(xy 46.99 243.84) (xy 46.99 242.57)
		)
		(stroke
			(width 0)
			(type default)
		)
	)
	(wire
		(pts
			(xy 104.14 250.19) (xy 104.14 248.92)
		)
		(stroke
			(width 0)
			(type default)
		)
	)
	(bus
		(pts
			(xy 316.23 166.37) (xy 316.23 168.91)
		)
		(stroke
			(width 0)
			(type default)
		)
	)
	(wire
		(pts
			(xy 104.14 243.84) (xy 104.14 242.57)
		)
		(stroke
			(width 0)
			(type default)
		)
	)
	(wire
		(pts
			(xy 124.46 250.19) (xy 124.46 248.92)
		)
		(stroke
			(width 0)
			(type default)
		)
	)
	(wire
		(pts
			(xy 130.81 62.23) (xy 148.59 62.23)
		)
		(stroke
			(width 0)
			(type default)
		)
	)
	(bus
		(pts
			(xy 231.14 135.89) (xy 231.14 138.43)
		)
		(stroke
			(width 0)
			(type default)
		)
	)
	(wire
		(pts
			(xy 260.35 240.03) (xy 260.35 242.57)
		)
		(stroke
			(width 0)
			(type default)
		)
	)
	(wire
		(pts
			(xy 130.81 97.79) (xy 148.59 97.79)
		)
		(stroke
			(width 0)
			(type default)
		)
	)
	(wire
		(pts
			(xy 134.62 242.57) (xy 134.62 243.84)
		)
		(stroke
			(width 0)
			(type default)
		)
	)
	(wire
		(pts
			(xy 233.68 80.01) (xy 243.84 80.01)
		)
		(stroke
			(width 0)
			(type default)
		)
	)
	(bus
		(pts
			(xy 231.14 85.09) (xy 231.14 90.17)
		)
		(stroke
			(width 0)
			(type default)
		)
	)
	(bus
		(pts
			(xy 39.37 46.99) (xy 39.37 55.88)
		)
		(stroke
			(width 0)
			(type default)
		)
	)
	(wire
		(pts
			(xy 233.68 64.77) (xy 243.84 64.77)
		)
		(stroke
			(width 0)
			(type default)
		)
	)
	(wire
		(pts
			(xy 236.22 257.81) (xy 240.03 257.81)
		)
		(stroke
			(width 0)
			(type default)
		)
	)
	(bus
		(pts
			(xy 39.37 71.12) (xy 39.37 73.66)
		)
		(stroke
			(width 0)
			(type default)
		)
	)
	(wire
		(pts
			(xy 154.94 234.95) (xy 154.94 236.22)
		)
		(stroke
			(width 0)
			(type default)
		)
	)
	(wire
		(pts
			(xy 233.68 120.65) (xy 243.84 120.65)
		)
		(stroke
			(width 0)
			(type default)
		)
	)
	(wire
		(pts
			(xy 243.84 240.03) (xy 251.46 240.03)
		)
		(stroke
			(width 0)
			(type default)
		)
	)
	(bus
		(pts
			(xy 128.27 59.69) (xy 128.27 62.23)
		)
		(stroke
			(width 0)
			(type default)
		)
	)
	(bus
		(pts
			(xy 128.27 156.21) (xy 128.27 158.75)
		)
		(stroke
			(width 0)
			(type default)
		)
	)
	(bus
		(pts
			(xy 231.14 176.53) (xy 231.14 179.07)
		)
		(stroke
			(width 0)
			(type default)
		)
	)
	(bus
		(pts
			(xy 231.14 156.21) (xy 231.14 158.75)
		)
		(stroke
			(width 0)
			(type default)
		)
	)
	(bus
		(pts
			(xy 39.37 177.8) (xy 39.37 180.34)
		)
		(stroke
			(width 0)
			(type default)
		)
	)
	(wire
		(pts
			(xy 233.68 176.53) (xy 243.84 176.53)
		)
		(stroke
			(width 0)
			(type default)
		)
	)
	(wire
		(pts
			(xy 233.68 72.39) (xy 243.84 72.39)
		)
		(stroke
			(width 0)
			(type default)
		)
	)
	(wire
		(pts
			(xy 114.3 234.95) (xy 134.62 234.95)
		)
		(stroke
			(width 0)
			(type default)
		)
	)
	(wire
		(pts
			(xy 317.5 58.42) (xy 345.44 58.42)
		)
		(stroke
			(width 0)
			(type default)
		)
	)
	(bus
		(pts
			(xy 316.23 132.08) (xy 316.23 133.35)
		)
		(stroke
			(width 0)
			(type default)
		)
	)
	(bus
		(pts
			(xy 128.27 125.73) (xy 128.27 128.27)
		)
		(stroke
			(width 0)
			(type default)
		)
	)
	(bus
		(pts
			(xy 128.27 67.31) (xy 128.27 69.85)
		)
		(stroke
			(width 0)
			(type default)
		)
	)
	(bus
		(pts
			(xy 316.23 67.31) (xy 316.23 69.85)
		)
		(stroke
			(width 0)
			(type default)
		)
	)
	(wire
		(pts
			(xy 41.91 132.08) (xy 52.07 132.08)
		)
		(stroke
			(width 0)
			(type default)
		)
	)
	(wire
		(pts
			(xy 256.54 240.03) (xy 260.35 240.03)
		)
		(stroke
			(width 0)
			(type default)
		)
	)
	(wire
		(pts
			(xy 130.81 82.55) (xy 148.59 82.55)
		)
		(stroke
			(width 0)
			(type default)
		)
	)
	(wire
		(pts
			(xy 83.82 250.19) (xy 83.82 248.92)
		)
		(stroke
			(width 0)
			(type default)
		)
	)
	(wire
		(pts
			(xy 41.91 114.3) (xy 52.07 114.3)
		)
		(stroke
			(width 0)
			(type default)
		)
	)
	(polyline
		(pts
			(xy 300.355 201.93) (xy 300.355 252.095)
		)
		(stroke
			(width 0)
			(type default)
		)
	)
	(wire
		(pts
			(xy 130.81 186.69) (xy 148.59 186.69)
		)
		(stroke
			(width 0)
			(type default)
		)
	)
	(wire
		(pts
			(xy 76.2 34.29) (xy 95.25 34.29)
		)
		(stroke
			(width 0)
			(type default)
		)
	)
	(wire
		(pts
			(xy 317.5 139.7) (xy 345.44 139.7)
		)
		(stroke
			(width 0)
			(type default)
		)
	)
	(wire
		(pts
			(xy 41.91 127) (xy 52.07 127)
		)
		(stroke
			(width 0)
			(type default)
		)
	)
	(bus
		(pts
			(xy 314.96 54.61) (xy 316.23 55.88)
		)
		(stroke
			(width 0)
			(type default)
		)
	)
	(bus
		(pts
			(xy 316.23 72.39) (xy 316.23 74.93)
		)
		(stroke
			(width 0)
			(type default)
		)
	)
	(wire
		(pts
			(xy 317.5 83.82) (xy 345.44 83.82)
		)
		(stroke
			(width 0)
			(type default)
		)
	)
	(bus
		(pts
			(xy 316.23 151.13) (xy 316.23 161.29)
		)
		(stroke
			(width 0)
			(type default)
		)
	)
	(wire
		(pts
			(xy 130.81 138.43) (xy 148.59 138.43)
		)
		(stroke
			(width 0)
			(type default)
		)
	)
	(wire
		(pts
			(xy 317.5 78.74) (xy 345.44 78.74)
		)
		(stroke
			(width 0)
			(type default)
		)
	)
	(wire
		(pts
			(xy 335.28 232.41) (xy 345.44 232.41)
		)
		(stroke
			(width 0)
			(type default)
		)
	)
	(bus
		(pts
			(xy 231.14 105.41) (xy 231.14 107.95)
		)
		(stroke
			(width 0)
			(type default)
		)
	)
	(wire
		(pts
			(xy 243.84 257.81) (xy 251.46 257.81)
		)
		(stroke
			(width 0)
			(type default)
		)
	)
	(wire
		(pts
			(xy 41.91 86.36) (xy 52.07 86.36)
		)
		(stroke
			(width 0)
			(type default)
		)
	)
	(bus
		(pts
			(xy 39.37 137.16) (xy 39.37 139.7)
		)
		(stroke
			(width 0)
			(type default)
		)
	)
	(bus
		(pts
			(xy 73.66 34.29) (xy 73.66 38.1)
		)
		(stroke
			(width 0)
			(type default)
		)
	)
	(wire
		(pts
			(xy 41.91 104.14) (xy 52.07 104.14)
		)
		(stroke
			(width 0)
			(type default)
		)
	)
	(bus
		(pts
			(xy 73.66 24.13) (xy 73.66 26.67)
		)
		(stroke
			(width 0)
			(type default)
		)
	)
	(bus
		(pts
			(xy 231.14 115.57) (xy 231.14 118.11)
		)
		(stroke
			(width 0)
			(type default)
		)
	)
	(wire
		(pts
			(xy 345.44 236.22) (xy 346.71 236.22)
		)
		(stroke
			(width 0)
			(type default)
		)
	)
	(wire
		(pts
			(xy 142.24 52.07) (xy 148.59 52.07)
		)
		(stroke
			(width 0)
			(type default)
		)
	)
	(bus
		(pts
			(xy 128.27 97.79) (xy 128.27 100.33)
		)
		(stroke
			(width 0)
			(type default)
		)
	)
	(wire
		(pts
			(xy 233.68 100.33) (xy 243.84 100.33)
		)
		(stroke
			(width 0)
			(type default)
		)
	)
	(bus
		(pts
			(xy 39.37 88.9) (xy 39.37 91.44)
		)
		(stroke
			(width 0)
			(type default)
		)
	)
	(wire
		(pts
			(xy 93.98 241.3) (xy 93.98 242.57)
		)
		(stroke
			(width 0)
			(type default)
		)
	)
	(wire
		(pts
			(xy 233.68 95.25) (xy 243.84 95.25)
		)
		(stroke
			(width 0)
			(type default)
		)
	)
	(wire
		(pts
			(xy 233.68 153.67) (xy 243.84 153.67)
		)
		(stroke
			(width 0)
			(type default)
		)
	)
	(wire
		(pts
			(xy 41.91 137.16) (xy 52.07 137.16)
		)
		(stroke
			(width 0)
			(type default)
		)
	)
	(bus
		(pts
			(xy 231.14 140.97) (xy 231.14 143.51)
		)
		(stroke
			(width 0)
			(type default)
		)
	)
	(wire
		(pts
			(xy 317.5 91.44) (xy 345.44 91.44)
		)
		(stroke
			(width 0)
			(type default)
		)
	)
	(wire
		(pts
			(xy 130.81 123.19) (xy 148.59 123.19)
		)
		(stroke
			(width 0)
			(type default)
		)
	)
	(wire
		(pts
			(xy 233.68 146.05) (xy 243.84 146.05)
		)
		(stroke
			(width 0)
			(type default)
		)
	)
	(wire
		(pts
			(xy 130.81 151.13) (xy 148.59 151.13)
		)
		(stroke
			(width 0)
			(type default)
		)
	)
	(wire
		(pts
			(xy 41.91 170.18) (xy 52.07 170.18)
		)
		(stroke
			(width 0)
			(type default)
		)
	)
	(wire
		(pts
			(xy 46.99 232.41) (xy 46.99 234.95)
		)
		(stroke
			(width 0)
			(type default)
		)
	)
	(bus
		(pts
			(xy 231.14 173.99) (xy 231.14 176.53)
		)
		(stroke
			(width 0)
			(type default)
		)
	)
	(wire
		(pts
			(xy 142.24 48.26) (xy 142.24 52.07)
		)
		(stroke
			(width 0)
			(type default)
		)
	)
	(wire
		(pts
			(xy 41.91 149.86) (xy 52.07 149.86)
		)
		(stroke
			(width 0)
			(type default)
		)
	)
	(wire
		(pts
			(xy 344.17 49.53) (xy 344.17 50.8)
		)
		(stroke
			(width 0)
			(type default)
		)
	)
	(bus
		(pts
			(xy 231.14 143.51) (xy 231.14 146.05)
		)
		(stroke
			(width 0)
			(type default)
		)
	)
	(wire
		(pts
			(xy 41.91 66.04) (xy 52.07 66.04)
		)
		(stroke
			(width 0)
			(type default)
		)
	)
	(wire
		(pts
			(xy 335.28 88.9) (xy 345.44 88.9)
		)
		(stroke
			(width 0)
			(type default)
		)
	)
	(wire
		(pts
			(xy 130.81 184.15) (xy 148.59 184.15)
		)
		(stroke
			(width 0)
			(type default)
		)
	)
	(wire
		(pts
			(xy 46.99 226.06) (xy 46.99 227.33)
		)
		(stroke
			(width 0)
			(type default)
		)
	)
	(wire
		(pts
			(xy 233.68 54.61) (xy 243.84 54.61)
		)
		(stroke
			(width 0)
			(type default)
		)
	)
	(bus
		(pts
			(xy 39.37 132.08) (xy 39.37 134.62)
		)
		(stroke
			(width 0)
			(type default)
		)
	)
	(bus
		(pts
			(xy 72.39 16.51) (xy 73.66 17.78)
		)
		(stroke
			(width 0)
			(type default)
		)
	)
	(wire
		(pts
			(xy 317.5 172.72) (xy 345.44 172.72)
		)
		(stroke
			(width 0)
			(type default)
		)
	)
	(wire
		(pts
			(xy 233.68 102.87) (xy 243.84 102.87)
		)
		(stroke
			(width 0)
			(type default)
		)
	)
	(wire
		(pts
			(xy 134.62 234.95) (xy 154.94 234.95)
		)
		(stroke
			(width 0)
			(type default)
		)
	)
	(wire
		(pts
			(xy 241.3 48.26) (xy 241.3 52.07)
		)
		(stroke
			(width 0)
			(type default)
		)
	)
	(wire
		(pts
			(xy 130.81 120.65) (xy 148.59 120.65)
		)
		(stroke
			(width 0)
			(type default)
		)
	)
	(bus
		(pts
			(xy 39.37 129.54) (xy 39.37 132.08)
		)
		(stroke
			(width 0)
			(type default)
		)
	)
	(bus
		(pts
			(xy 312.42 93.98) (xy 312.42 96.52)
		)
		(stroke
			(width 0)
			(type default)
		)
	)
	(bus
		(pts
			(xy 39.37 167.64) (xy 39.37 170.18)
		)
		(stroke
			(width 0)
			(type default)
		)
	)
	(wire
		(pts
			(xy 148.59 105.41) (xy 130.81 105.41)
		)
		(stroke
			(width 0)
			(type default)
		)
	)
	(bus
		(pts
			(xy 128.27 161.29) (xy 128.27 163.83)
		)
		(stroke
			(width 0)
			(type default)
		)
	)
	(wire
		(pts
			(xy 41.91 78.74) (xy 52.07 78.74)
		)
		(stroke
			(width 0)
			(type default)
		)
	)
	(wire
		(pts
			(xy 76.2 26.67) (xy 95.25 26.67)
		)
		(stroke
			(width 0)
			(type default)
		)
	)
	(bus
		(pts
			(xy 231.14 45.72) (xy 231.14 57.15)
		)
		(stroke
			(width 0)
			(type default)
		)
	)
	(bus
		(pts
			(xy 231.14 74.93) (xy 231.14 77.47)
		)
		(stroke
			(width 0)
			(type default)
		)
	)
	(wire
		(pts
			(xy 130.81 128.27) (xy 148.59 128.27)
		)
		(stroke
			(width 0)
			(type default)
		)
	)
	(bus
		(pts
			(xy 316.23 176.53) (xy 316.23 179.07)
		)
		(stroke
			(width 0)
			(type default)
		)
	)
	(bus
		(pts
			(xy 73.66 29.21) (xy 73.66 31.75)
		)
		(stroke
			(width 0)
			(type default)
		)
	)
	(wire
		(pts
			(xy 41.91 91.44) (xy 52.07 91.44)
		)
		(stroke
			(width 0)
			(type default)
		)
	)
	(wire
		(pts
			(xy 233.68 140.97) (xy 243.84 140.97)
		)
		(stroke
			(width 0)
			(type default)
		)
	)
	(bus
		(pts
			(xy 316.23 168.91) (xy 316.23 171.45)
		)
		(stroke
			(width 0)
			(type default)
		)
	)
	(wire
		(pts
			(xy 233.68 59.69) (xy 243.84 59.69)
		)
		(stroke
			(width 0)
			(type default)
		)
	)
	(wire
		(pts
			(xy 233.68 105.41) (xy 243.84 105.41)
		)
		(stroke
			(width 0)
			(type default)
		)
	)
	(wire
		(pts
			(xy 317.5 73.66) (xy 345.44 73.66)
		)
		(stroke
			(width 0)
			(type default)
		)
	)
	(wire
		(pts
			(xy 317.5 86.36) (xy 345.44 86.36)
		)
		(stroke
			(width 0)
			(type default)
		)
	)
	(wire
		(pts
			(xy 345.44 232.41) (xy 345.44 236.22)
		)
		(stroke
			(width 0)
			(type default)
		)
	)
	(bus
		(pts
			(xy 231.14 158.75) (xy 231.14 161.29)
		)
		(stroke
			(width 0)
			(type default)
		)
	)
	(bus
		(pts
			(xy 39.37 149.86) (xy 39.37 154.94)
		)
		(stroke
			(width 0)
			(type default)
		)
	)
	(wire
		(pts
			(xy 233.68 186.69) (xy 243.84 186.69)
		)
		(stroke
			(width 0)
			(type default)
		)
	)
	(bus
		(pts
			(xy 73.66 17.78) (xy 73.66 21.59)
		)
		(stroke
			(width 0)
			(type default)
		)
	)
	(wire
		(pts
			(xy 233.68 82.55) (xy 243.84 82.55)
		)
		(stroke
			(width 0)
			(type default)
		)
	)
	(wire
		(pts
			(xy 233.68 143.51) (xy 243.84 143.51)
		)
		(stroke
			(width 0)
			(type default)
		)
	)
	(wire
		(pts
			(xy 130.81 140.97) (xy 148.59 140.97)
		)
		(stroke
			(width 0)
			(type default)
		)
	)
	(wire
		(pts
			(xy 233.68 113.03) (xy 243.84 113.03)
		)
		(stroke
			(width 0)
			(type default)
		)
	)
	(bus
		(pts
			(xy 314.96 130.81) (xy 316.23 132.08)
		)
		(stroke
			(width 0)
			(type default)
		)
	)
	(bus
		(pts
			(xy 39.37 96.52) (xy 39.37 99.06)
		)
		(stroke
			(width 0)
			(type default)
		)
	)
	(wire
		(pts
			(xy 130.81 166.37) (xy 148.59 166.37)
		)
		(stroke
			(width 0)
			(type default)
		)
	)
	(wire
		(pts
			(xy 130.81 80.01) (xy 148.59 80.01)
		)
		(stroke
			(width 0)
			(type default)
		)
	)
	(bus
		(pts
			(xy 39.37 180.34) (xy 39.37 182.88)
		)
		(stroke
			(width 0)
			(type default)
		)
	)
	(wire
		(pts
			(xy 41.91 175.26) (xy 52.07 175.26)
		)
		(stroke
			(width 0)
			(type default)
		)
	)
	(wire
		(pts
			(xy 241.3 52.07) (xy 243.84 52.07)
		)
		(stroke
			(width 0)
			(type default)
		)
	)
	(wire
		(pts
			(xy 130.81 107.95) (xy 148.59 107.95)
		)
		(stroke
			(width 0)
			(type default)
		)
	)
	(wire
		(pts
			(xy 130.81 100.33) (xy 148.59 100.33)
		)
		(stroke
			(width 0)
			(type default)
		)
	)
	(wire
		(pts
			(xy 317.5 182.88) (xy 345.44 182.88)
		)
		(stroke
			(width 0)
			(type default)
		)
	)
	(bus
		(pts
			(xy 316.23 138.43) (xy 316.23 140.97)
		)
		(stroke
			(width 0)
			(type default)
		)
	)
	(bus
		(pts
			(xy 39.37 68.58) (xy 39.37 71.12)
		)
		(stroke
			(width 0)
			(type default)
		)
	)
	(bus
		(pts
			(xy 39.37 111.76) (xy 39.37 114.3)
		)
		(stroke
			(width 0)
			(type default)
		)
	)
	(wire
		(pts
			(xy 41.91 99.06) (xy 52.07 99.06)
		)
		(stroke
			(width 0)
			(type default)
		)
	)
	(polyline
		(pts
			(xy 12.7 201.93) (xy 407.67 201.93)
		)
		(stroke
			(width 0)
			(type default)
		)
	)
	(wire
		(pts
			(xy 130.81 153.67) (xy 148.59 153.67)
		)
		(stroke
			(width 0)
			(type default)
		)
	)
	(wire
		(pts
			(xy 144.78 243.84) (xy 144.78 242.57)
		)
		(stroke
			(width 0)
			(type default)
		)
	)
	(wire
		(pts
			(xy 130.81 77.47) (xy 148.59 77.47)
		)
		(stroke
			(width 0)
			(type default)
		)
	)
	(wire
		(pts
			(xy 317.5 152.4) (xy 345.44 152.4)
		)
		(stroke
			(width 0)
			(type default)
		)
	)
	(bus
		(pts
			(xy 231.14 110.49) (xy 231.14 113.03)
		)
		(stroke
			(width 0)
			(type default)
		)
	)
	(wire
		(pts
			(xy 93.98 234.95) (xy 114.3 234.95)
		)
		(stroke
			(width 0)
			(type default)
		)
	)
	(wire
		(pts
			(xy 130.81 54.61) (xy 148.59 54.61)
		)
		(stroke
			(width 0)
			(type default)
		)
	)
	(wire
		(pts
			(xy 335.28 233.68) (xy 335.28 232.41)
		)
		(stroke
			(width 0)
			(type default)
		)
	)
	(wire
		(pts
			(xy 41.91 63.5) (xy 52.07 63.5)
		)
		(stroke
			(width 0)
			(type default)
		)
	)
	(wire
		(pts
			(xy 233.68 77.47) (xy 243.84 77.47)
		)
		(stroke
			(width 0)
			(type default)
		)
	)
	(wire
		(pts
			(xy 41.91 185.42) (xy 52.07 185.42)
		)
		(stroke
			(width 0)
			(type default)
		)
	)
	(bus
		(pts
			(xy 231.14 64.77) (xy 231.14 67.31)
		)
		(stroke
			(width 0)
			(type default)
		)
	)
	(wire
		(pts
			(xy 52.07 49.53) (xy 52.07 50.8)
		)
		(stroke
			(width 0)
			(type default)
		)
	)
	(bus
		(pts
			(xy 231.14 113.03) (xy 231.14 115.57)
		)
		(stroke
			(width 0)
			(type default)
		)
	)
	(bus
		(pts
			(xy 316.23 133.35) (xy 316.23 135.89)
		)
		(stroke
			(width 0)
			(type default)
		)
	)
	(wire
		(pts
			(xy 233.68 148.59) (xy 243.84 148.59)
		)
		(stroke
			(width 0)
			(type default)
		)
	)
	(bus
		(pts
			(xy 39.37 142.24) (xy 39.37 144.78)
		)
		(stroke
			(width 0)
			(type default)
		)
	)
	(label "B.DQS1_N"
		(at 233.68 95.25 0)
		(effects
			(font
				(size 1.27 1.27)
			)
			(justify left bottom)
		)
	)
	(label "A.CA4"
		(at 130.81 97.79 0)
		(effects
			(font
				(size 1.27 1.27)
			)
			(justify left bottom)
		)
	)
	(label "VREF_65"
		(at 130.81 54.61 0)
		(effects
			(font
				(size 1.27 1.27)
			)
			(justify left bottom)
		)
	)
	(label "B.DQ30"
		(at 233.68 181.61 0)
		(effects
			(font
				(size 1.27 1.27)
			)
			(justify left bottom)
		)
	)
	(label "B.CA6"
		(at 130.81 135.89 0)
		(effects
			(font
				(size 1.27 1.27)
			)
			(justify left bottom)
		)
	)
	(label "A.CB2"
		(at 130.81 69.85 0)
		(effects
			(font
				(size 1.27 1.27)
			)
			(justify left bottom)
		)
	)
	(label "B.DQ8"
		(at 233.68 100.33 0)
		(effects
			(font
				(size 1.27 1.27)
			)
			(justify left bottom)
		)
	)
	(label "A.DQ13"
		(at 41.91 149.86 0)
		(effects
			(font
				(size 1.27 1.27)
			)
			(justify left bottom)
		)
	)
	(label "A.DQ11"
		(at 41.91 132.08 0)
		(effects
			(font
				(size 1.27 1.27)
			)
			(justify left bottom)
		)
	)
	(label "CTRL.~{ALERT}"
		(at 130.81 123.19 0)
		(effects
			(font
				(size 1.27 1.27)
			)
			(justify left bottom)
		)
	)
	(label "A.DQS1_P"
		(at 41.91 124.46 0)
		(effects
			(font
				(size 1.27 1.27)
			)
			(justify left bottom)
		)
	)
	(label "A.DQ5"
		(at 41.91 182.88 0)
		(effects
			(font
				(size 1.27 1.27)
			)
			(justify left bottom)
		)
	)
	(label "B.DQ7"
		(at 233.68 82.55 0)
		(effects
			(font
				(size 1.27 1.27)
			)
			(justify left bottom)
		)
	)
	(label "ETH.RXC"
		(at 317.5 175.26 0)
		(effects
			(font
				(size 1.27 1.27)
			)
			(justify left bottom)
		)
	)
	(label "A.DQS4_N"
		(at 130.81 62.23 0)
		(effects
			(font
				(size 1.27 1.27)
			)
			(justify left bottom)
		)
	)
	(label "HyperRAM.~{RESET}"
		(at 317.5 60.96 0)
		(effects
			(font
				(size 1.27 1.27)
			)
			(justify left bottom)
		)
	)
	(label "B.DQ28"
		(at 233.68 186.69 0)
		(effects
			(font
				(size 1.27 1.27)
			)
			(justify left bottom)
		)
	)
	(label "B.DQ12"
		(at 233.68 120.65 0)
		(effects
			(font
				(size 1.27 1.27)
			)
			(justify left bottom)
		)
	)
	(label "HyperRAM.DQ2"
		(at 317.5 68.58 0)
		(effects
			(font
				(size 1.27 1.27)
			)
			(justify left bottom)
		)
	)
	(label "B.CB6"
		(at 130.81 168.91 0)
		(effects
			(font
				(size 1.27 1.27)
			)
			(justify left bottom)
		)
	)
	(label "A.DQS4_P"
		(at 130.81 59.69 0)
		(effects
			(font
				(size 1.27 1.27)
			)
			(justify left bottom)
		)
	)
	(label "VRP_65"
		(at 243.84 240.03 0)
		(effects
			(font
				(size 1.27 1.27)
			)
			(justify left bottom)
		)
	)
	(label "ETH.TXD0"
		(at 317.5 144.78 0)
		(effects
			(font
				(size 1.27 1.27)
			)
			(justify left bottom)
		)
	)
	(label "HyperRAM.DQ7"
		(at 317.5 66.04 0)
		(effects
			(font
				(size 1.27 1.27)
			)
			(justify left bottom)
		)
	)
	(label "A.CS0_c"
		(at 130.81 92.71 0)
		(effects
			(font
				(size 1.27 1.27)
			)
			(justify left bottom)
		)
	)
	(label "A.CA5"
		(at 130.81 100.33 0)
		(effects
			(font
				(size 1.27 1.27)
			)
			(justify left bottom)
		)
	)
	(label "B.CB0"
		(at 130.81 181.61 0)
		(effects
			(font
				(size 1.27 1.27)
			)
			(justify left bottom)
		)
	)
	(label "B.DQS2_P"
		(at 233.68 125.73 0)
		(effects
			(font
				(size 1.27 1.27)
			)
			(justify left bottom)
		)
	)
	(label "B.DQ0"
		(at 233.68 67.31 0)
		(effects
			(font
				(size 1.27 1.27)
			)
			(justify left bottom)
		)
	)
	(label "CTRL.DLBDQ"
		(at 95.25 26.67 180)
		(effects
			(font
				(size 1.27 1.27)
			)
			(justify right bottom)
		)
	)
	(label "B.DQ17"
		(at 233.68 135.89 0)
		(effects
			(font
				(size 1.27 1.27)
			)
			(justify left bottom)
		)
	)
	(label "VREF"
		(at 91.44 234.95 180)
		(effects
			(font
				(size 1.27 1.27)
			)
			(justify right bottom)
		)
	)
	(label "B.DQS5_P"
		(at 233.68 74.93 0)
		(effects
			(font
				(size 1.27 1.27)
			)
			(justify left bottom)
		)
	)
	(label "CTRL.CK_N"
		(at 95.25 34.29 180)
		(effects
			(font
				(size 1.27 1.27)
			)
			(justify right bottom)
		)
	)
	(label "ETH.RX_CTL"
		(at 317.5 172.72 0)
		(effects
			(font
				(size 1.27 1.27)
			)
			(justify left bottom)
		)
	)
	(label "HyperRAM.DQ5"
		(at 317.5 63.5 0)
		(effects
			(font
				(size 1.27 1.27)
			)
			(justify left bottom)
		)
	)
	(label "HyperRAM.DQ4"
		(at 317.5 81.28 0)
		(effects
			(font
				(size 1.27 1.27)
			)
			(justify left bottom)
		)
	)
	(label "GCLK_100_LVDS+"
		(at 325.12 129.54 0)
		(effects
			(font
				(size 1.27 1.27)
			)
			(justify left bottom)
		)
	)
	(label "B.DQ29"
		(at 233.68 184.15 0)
		(effects
			(font
				(size 1.27 1.27)
			)
			(justify left bottom)
		)
	)
	(label "A.PAR"
		(at 130.81 120.65 0)
		(effects
			(font
				(size 1.27 1.27)
			)
			(justify left bottom)
		)
	)
	(label "A.DQ1"
		(at 41.91 167.64 0)
		(effects
			(font
				(size 1.27 1.27)
			)
			(justify left bottom)
		)
	)
	(label "B.DQ14"
		(at 233.68 118.11 0)
		(effects
			(font
				(size 1.27 1.27)
			)
			(justify left bottom)
		)
	)
	(label "B.DQ25"
		(at 233.68 168.91 0)
		(effects
			(font
				(size 1.27 1.27)
			)
			(justify left bottom)
		)
	)
	(label "A.DQ0"
		(at 41.91 162.56 0)
		(effects
			(font
				(size 1.27 1.27)
			)
			(justify left bottom)
		)
	)
	(label "B.CA1"
		(at 130.81 151.13 0)
		(effects
			(font
				(size 1.27 1.27)
			)
			(justify left bottom)
		)
	)
	(label "B.CA3"
		(at 130.81 148.59 0)
		(effects
			(font
				(size 1.27 1.27)
			)
			(justify left bottom)
		)
	)
	(label "A.DQ31"
		(at 41.91 83.82 0)
		(effects
			(font
				(size 1.27 1.27)
			)
			(justify left bottom)
		)
	)
	(label "ETH.~{INT}"
		(at 317.5 180.34 0)
		(effects
			(font
				(size 1.27 1.27)
			)
			(justify left bottom)
		)
	)
	(label "CTRL.~{ALERT}"
		(at 95.25 29.21 180)
		(effects
			(font
				(size 1.27 1.27)
			)
			(justify right bottom)
		)
	)
	(label "B.DQ6"
		(at 233.68 85.09 0)
		(effects
			(font
				(size 1.27 1.27)
			)
			(justify left bottom)
		)
	)
	(label "HyperRAM.DQ3"
		(at 317.5 71.12 0)
		(effects
			(font
				(size 1.27 1.27)
			)
			(justify left bottom)
		)
	)
	(label "VREF_67"
		(at 144.78 242.57 0)
		(effects
			(font
				(size 1.27 1.27)
			)
			(justify left bottom)
		)
	)
	(label "A.DQ21"
		(at 41.91 114.3 0)
		(effects
			(font
				(size 1.27 1.27)
			)
			(justify left bottom)
		)
	)
	(label "B.DQ20"
		(at 233.68 148.59 0)
		(effects
			(font
				(size 1.27 1.27)
			)
			(justify left bottom)
		)
	)
	(label "A.DQ23"
		(at 41.91 119.38 0)
		(effects
			(font
				(size 1.27 1.27)
			)
			(justify left bottom)
		)
	)
	(label "A.DQS3_N"
		(at 41.91 60.96 0)
		(effects
			(font
				(size 1.27 1.27)
			)
			(justify left bottom)
		)
	)
	(label "ETH.REF_CLK"
		(at 317.5 170.18 0)
		(effects
			(font
				(size 1.27 1.27)
			)
			(justify left bottom)
		)
	)
	(label "B.DQS1_P"
		(at 233.68 92.71 0)
		(effects
			(font
				(size 1.27 1.27)
			)
			(justify left bottom)
		)
	)
	(label "B.DQS0_N"
		(at 233.68 62.23 0)
		(effects
			(font
				(size 1.27 1.27)
			)
			(justify left bottom)
		)
	)
	(label "GCLK_100_LVDS+"
		(at 384.81 236.22 180)
		(effects
			(font
				(size 1.27 1.27)
			)
			(justify right bottom)
		)
	)
	(label "B.DQ22"
		(at 233.68 146.05 0)
		(effects
			(font
				(size 1.27 1.27)
			)
			(justify left bottom)
		)
	)
	(label "A.DQS7_P"
		(at 41.91 106.68 0)
		(effects
			(font
				(size 1.27 1.27)
			)
			(justify left bottom)
		)
	)
	(label "A.DQ29"
		(at 41.91 86.36 0)
		(effects
			(font
				(size 1.27 1.27)
			)
			(justify left bottom)
		)
	)
	(label "A.DQ8"
		(at 41.91 134.62 0)
		(effects
			(font
				(size 1.27 1.27)
			)
			(justify left bottom)
		)
	)
	(label "CTRL.CK_P"
		(at 130.81 107.95 0)
		(effects
			(font
				(size 1.27 1.27)
			)
			(justify left bottom)
		)
	)
	(label "VRP_67"
		(at 335.28 88.9 0)
		(effects
			(font
				(size 1.27 1.27)
			)
			(justify left bottom)
		)
	)
	(label "B.DQ31"
		(at 233.68 179.07 0)
		(effects
			(font
				(size 1.27 1.27)
			)
			(justify left bottom)
		)
	)
	(label "A.CA6"
		(at 130.81 118.11 0)
		(effects
			(font
				(size 1.27 1.27)
			)
			(justify left bottom)
		)
	)
	(label "B.DQ3"
		(at 233.68 72.39 0)
		(effects
			(font
				(size 1.27 1.27)
			)
			(justify left bottom)
		)
	)
	(label "B.DQS3_N"
		(at 233.68 161.29 0)
		(effects
			(font
				(size 1.27 1.27)
			)
			(justify left bottom)
		)
	)
	(label "VRP_67"
		(at 243.84 257.81 0)
		(effects
			(font
				(size 1.27 1.27)
			)
			(justify left bottom)
		)
	)
	(label "A.CB7"
		(at 130.81 85.09 0)
		(effects
			(font
				(size 1.27 1.27)
			)
			(justify left bottom)
		)
	)
	(label "B.DQS9_N"
		(at 130.81 161.29 0)
		(effects
			(font
				(size 1.27 1.27)
			)
			(justify left bottom)
		)
	)
	(label "B.DQ5"
		(at 233.68 87.63 0)
		(effects
			(font
				(size 1.27 1.27)
			)
			(justify left bottom)
		)
	)
	(label "A.DQS5_N"
		(at 41.91 175.26 0)
		(effects
			(font
				(size 1.27 1.27)
			)
			(justify left bottom)
		)
	)
	(label "A.DQ19"
		(at 41.91 104.14 0)
		(effects
			(font
				(size 1.27 1.27)
			)
			(justify left bottom)
		)
	)
	(label "A.CS1_c"
		(at 130.81 95.25 0)
		(effects
			(font
				(size 1.27 1.27)
			)
			(justify left bottom)
		)
	)
	(label "A.DQ26"
		(at 41.91 66.04 0)
		(effects
			(font
				(size 1.27 1.27)
			)
			(justify left bottom)
		)
	)
	(label "HyperRAM.DQ1"
		(at 317.5 86.36 0)
		(effects
			(font
				(size 1.27 1.27)
			)
			(justify left bottom)
		)
	)
	(label "A.DQ6"
		(at 41.91 180.34 0)
		(effects
			(font
				(size 1.27 1.27)
			)
			(justify left bottom)
		)
	)
	(label "B.DQ2"
		(at 233.68 69.85 0)
		(effects
			(font
				(size 1.27 1.27)
			)
			(justify left bottom)
		)
	)
	(label "B.DQS3_P"
		(at 233.68 158.75 0)
		(effects
			(font
				(size 1.27 1.27)
			)
			(justify left bottom)
		)
	)
	(label "VREF_64"
		(at 83.82 242.57 0)
		(effects
			(font
				(size 1.27 1.27)
			)
			(justify left bottom)
		)
	)
	(label "B.DQ27"
		(at 233.68 171.45 0)
		(effects
			(font
				(size 1.27 1.27)
			)
			(justify left bottom)
		)
	)
	(label "HyperRAM.CK_N"
		(at 317.5 76.2 0)
		(effects
			(font
				(size 1.27 1.27)
			)
			(justify left bottom)
		)
	)
	(label "B.CA2"
		(at 130.81 130.81 0)
		(effects
			(font
				(size 1.27 1.27)
			)
			(justify left bottom)
		)
	)
	(label "SD.CD"
		(at 314.96 109.22 0)
		(effects
			(font
				(size 1.27 1.27)
			)
			(justify left bottom)
		)
	)
	(label "A.CA0"
		(at 130.81 115.57 0)
		(effects
			(font
				(size 1.27 1.27)
			)
			(justify left bottom)
		)
	)
	(label "A.DQ10"
		(at 41.91 129.54 0)
		(effects
			(font
				(size 1.27 1.27)
			)
			(justify left bottom)
		)
	)
	(label "ETH.TX_CTL"
		(at 317.5 165.1 0)
		(effects
			(font
				(size 1.27 1.27)
			)
			(justify left bottom)
		)
	)
	(label "B.DQS6_N"
		(at 233.68 110.49 0)
		(effects
			(font
				(size 1.27 1.27)
			)
			(justify left bottom)
		)
	)
	(label "A.DQ4"
		(at 41.91 185.42 0)
		(effects
			(font
				(size 1.27 1.27)
			)
			(justify left bottom)
		)
	)
	(label "A.DQS6_P"
		(at 41.91 139.7 0)
		(effects
			(font
				(size 1.27 1.27)
			)
			(justify left bottom)
		)
	)
	(label "ETH.~{RESET}"
		(at 317.5 167.64 0)
		(effects
			(font
				(size 1.27 1.27)
			)
			(justify left bottom)
		)
	)
	(label "B.PAR"
		(at 130.81 153.67 0)
		(effects
			(font
				(size 1.27 1.27)
			)
			(justify left bottom)
		)
	)
	(label "SD.DAT2"
		(at 314.96 99.06 0)
		(effects
			(font
				(size 1.27 1.27)
			)
			(justify left bottom)
		)
	)
	(label "B.CA0"
		(at 130.81 133.35 0)
		(effects
			(font
				(size 1.27 1.27)
			)
			(justify left bottom)
		)
	)
	(label "CTRL.DLBDQS"
		(at 130.81 143.51 0)
		(effects
			(font
				(size 1.27 1.27)
			)
			(justify left bottom)
		)
	)
	(label "B.DQ1"
		(at 233.68 64.77 0)
		(effects
			(font
				(size 1.27 1.27)
			)
			(justify left bottom)
		)
	)
	(label "A.DQS6_N"
		(at 41.91 142.24 0)
		(effects
			(font
				(size 1.27 1.27)
			)
			(justify left bottom)
		)
	)
	(label "ETH.RXD1"
		(at 317.5 137.16 0)
		(effects
			(font
				(size 1.27 1.27)
			)
			(justify left bottom)
		)
	)
	(label "B.DQ26"
		(at 233.68 166.37 0)
		(effects
			(font
				(size 1.27 1.27)
			)
			(justify left bottom)
		)
	)
	(label "VREF_64"
		(at 41.91 53.34 0)
		(effects
			(font
				(size 1.27 1.27)
			)
			(justify left bottom)
		)
	)
	(label "A.DQ3"
		(at 41.91 170.18 0)
		(effects
			(font
				(size 1.27 1.27)
			)
			(justify left bottom)
		)
	)
	(label "A.DQS2_P"
		(at 41.91 91.44 0)
		(effects
			(font
				(size 1.27 1.27)
			)
			(justify left bottom)
		)
	)
	(label "CTRL.DLBDQ"
		(at 130.81 140.97 0)
		(effects
			(font
				(size 1.27 1.27)
			)
			(justify left bottom)
		)
	)
	(label "A.DQ30"
		(at 41.91 81.28 0)
		(effects
			(font
				(size 1.27 1.27)
			)
			(justify left bottom)
		)
	)
	(label "A.CB1"
		(at 130.81 64.77 0)
		(effects
			(font
				(size 1.27 1.27)
			)
			(justify left bottom)
		)
	)
	(label "B.CA4"
		(at 130.81 146.05 0)
		(effects
			(font
				(size 1.27 1.27)
			)
			(justify left bottom)
		)
	)
	(label "A.DQ24"
		(at 41.91 63.5 0)
		(effects
			(font
				(size 1.27 1.27)
			)
			(justify left bottom)
		)
	)
	(label "ETH.TXD3"
		(at 317.5 139.7 0)
		(effects
			(font
				(size 1.27 1.27)
			)
			(justify left bottom)
		)
	)
	(label "VREF_66"
		(at 124.46 242.57 0)
		(effects
			(font
				(size 1.27 1.27)
			)
			(justify left bottom)
		)
	)
	(label "A.CB3"
		(at 130.81 72.39 0)
		(effects
			(font
				(size 1.27 1.27)
			)
			(justify left bottom)
		)
	)
	(label "SD.DAT3"
		(at 314.96 106.68 0)
		(effects
			(font
				(size 1.27 1.27)
			)
			(justify left bottom)
		)
	)
	(label "B.CB1"
		(at 130.81 184.15 0)
		(effects
			(font
				(size 1.27 1.27)
			)
			(justify left bottom)
		)
	)
	(label "VRP_66"
		(at 233.68 90.17 0)
		(effects
			(font
				(size 1.27 1.27)
			)
			(justify left bottom)
		)
	)
	(label "HyperRAM.CK_P"
		(at 317.5 73.66 0)
		(effects
			(font
				(size 1.27 1.27)
			)
			(justify left bottom)
		)
	)
	(label "A.DQ9"
		(at 41.91 137.16 0)
		(effects
			(font
				(size 1.27 1.27)
			)
			(justify left bottom)
		)
	)
	(label "A.CA1"
		(at 130.81 113.03 0)
		(effects
			(font
				(size 1.27 1.27)
			)
			(justify left bottom)
		)
	)
	(label "A.DQ7"
		(at 41.91 177.8 0)
		(effects
			(font
				(size 1.27 1.27)
			)
			(justify left bottom)
		)
	)
	(label "B.DQ9"
		(at 233.68 97.79 0)
		(effects
			(font
				(size 1.27 1.27)
			)
			(justify left bottom)
		)
	)
	(label "VRP_66"
		(at 223.52 257.81 0)
		(effects
			(font
				(size 1.27 1.27)
			)
			(justify left bottom)
		)
	)
	(label "A.DQS9_N"
		(at 130.81 77.47 0)
		(effects
			(font
				(size 1.27 1.27)
			)
			(justify left bottom)
		)
	)
	(label "B.DQ10"
		(at 233.68 105.41 0)
		(effects
			(font
				(size 1.27 1.27)
			)
			(justify left bottom)
		)
	)
	(label "CTRL.CK_N"
		(at 130.81 110.49 0)
		(effects
			(font
				(size 1.27 1.27)
			)
			(justify left bottom)
		)
	)
	(label "B.DQS7_N"
		(at 233.68 143.51 0)
		(effects
			(font
				(size 1.27 1.27)
			)
			(justify left bottom)
		)
	)
	(label "B.DQ13"
		(at 233.68 115.57 0)
		(effects
			(font
				(size 1.27 1.27)
			)
			(justify left bottom)
		)
	)
	(label "CTRL.PWR_GOOD"
		(at 130.81 156.21 0)
		(effects
			(font
				(size 1.27 1.27)
			)
			(justify left bottom)
		)
	)
	(label "B.CB4"
		(at 130.81 163.83 0)
		(effects
			(font
				(size 1.27 1.27)
			)
			(justify left bottom)
		)
	)
	(label "B.CB2"
		(at 130.81 186.69 0)
		(effects
			(font
				(size 1.27 1.27)
			)
			(justify left bottom)
		)
	)
	(label "B.CB3"
		(at 130.81 179.07 0)
		(effects
			(font
				(size 1.27 1.27)
			)
			(justify left bottom)
		)
	)
	(label "B.CB7"
		(at 130.81 166.37 0)
		(effects
			(font
				(size 1.27 1.27)
			)
			(justify left bottom)
		)
	)
	(label "A.DQS1_N"
		(at 41.91 127 0)
		(effects
			(font
				(size 1.27 1.27)
			)
			(justify left bottom)
		)
	)
	(label "B.CA5"
		(at 130.81 138.43 0)
		(effects
			(font
				(size 1.27 1.27)
			)
			(justify left bottom)
		)
	)
	(label "ETH.MDC"
		(at 317.5 182.88 0)
		(effects
			(font
				(size 1.27 1.27)
			)
			(justify left bottom)
		)
	)
	(label "A.CB4"
		(at 130.81 82.55 0)
		(effects
			(font
				(size 1.27 1.27)
			)
			(justify left bottom)
		)
	)
	(label "HyperRAM.DQ0"
		(at 317.5 78.74 0)
		(effects
			(font
				(size 1.27 1.27)
			)
			(justify left bottom)
		)
	)
	(label "B.DQ11"
		(at 233.68 102.87 0)
		(effects
			(font
				(size 1.27 1.27)
			)
			(justify left bottom)
		)
	)
	(label "B.DQS2_N"
		(at 233.68 128.27 0)
		(effects
			(font
				(size 1.27 1.27)
			)
			(justify left bottom)
		)
	)
	(label "B.CS0_c"
		(at 130.81 125.73 0)
		(effects
			(font
				(size 1.27 1.27)
			)
			(justify left bottom)
		)
	)
	(label "ETH.TXD2"
		(at 317.5 152.4 0)
		(effects
			(font
				(size 1.27 1.27)
			)
			(justify left bottom)
		)
	)
	(label "SD.CLK"
		(at 314.96 96.52 0)
		(effects
			(font
				(size 1.27 1.27)
			)
			(justify left bottom)
		)
	)
	(label "CTRL.~{RESET}"
		(at 129.54 189.23 0)
		(effects
			(font
				(size 1.27 1.27)
			)
			(justify left bottom)
		)
	)
	(label "A.DQS8_P"
		(at 41.91 73.66 0)
		(effects
			(font
				(size 1.27 1.27)
			)
			(justify left bottom)
		)
	)
	(label "B.DQS5_N"
		(at 233.68 77.47 0)
		(effects
			(font
				(size 1.27 1.27)
			)
			(justify left bottom)
		)
	)
	(label "A.DQ15"
		(at 41.91 144.78 0)
		(effects
			(font
				(size 1.27 1.27)
			)
			(justify left bottom)
		)
	)
	(label "B.DQS4_P"
		(at 130.81 173.99 0)
		(effects
			(font
				(size 1.27 1.27)
			)
			(justify left bottom)
		)
	)
	(label "A.DQ14"
		(at 41.91 147.32 0)
		(effects
			(font
				(size 1.27 1.27)
			)
			(justify left bottom)
		)
	)
	(label "CTRL.DLBDQS"
		(at 95.25 24.13 180)
		(effects
			(font
				(size 1.27 1.27)
			)
			(justify right bottom)
		)
	)
	(label "A.DQS2_N"
		(at 41.91 93.98 0)
		(effects
			(font
				(size 1.27 1.27)
			)
			(justify left bottom)
		)
	)
	(label "B.DQ19"
		(at 233.68 138.43 0)
		(effects
			(font
				(size 1.27 1.27)
			)
			(justify left bottom)
		)
	)
	(label "A.DQS5_P"
		(at 41.91 172.72 0)
		(effects
			(font
				(size 1.27 1.27)
			)
			(justify left bottom)
		)
	)
	(label "CTRL.PWR_GOOD"
		(at 95.25 39.37 180)
		(effects
			(font
				(size 1.27 1.27)
			)
			(justify right bottom)
		)
	)
	(label "B.DQ24"
		(at 233.68 163.83 0)
		(effects
			(font
				(size 1.27 1.27)
			)
			(justify left bottom)
		)
	)
	(label "A.DQ17"
		(at 41.91 99.06 0)
		(effects
			(font
				(size 1.27 1.27)
			)
			(justify left bottom)
		)
	)
	(label "ETH.RXD2"
		(at 317.5 134.62 0)
		(effects
			(font
				(size 1.27 1.27)
			)
			(justify left bottom)
		)
	)
	(label "B.DQS8_P"
		(at 233.68 173.99 0)
		(effects
			(font
				(size 1.27 1.27)
			)
			(justify left bottom)
		)
	)
	(label "ETH.RXD0"
		(at 317.5 149.86 0)
		(effects
			(font
				(size 1.27 1.27)
			)
			(justify left bottom)
		)
	)
	(label "A.DQS9_P"
		(at 130.81 74.93 0)
		(effects
			(font
				(size 1.27 1.27)
			)
			(justify left bottom)
		)
	)
	(label "A.DQS0_N"
		(at 41.91 160.02 0)
		(effects
			(font
				(size 1.27 1.27)
			)
			(justify left bottom)
		)
	)
	(label "ETH.TXD1"
		(at 317.5 142.24 0)
		(effects
			(font
				(size 1.27 1.27)
			)
			(justify left bottom)
		)
	)
	(label "HyperRAM.DQ6"
		(at 317.5 83.82 0)
		(effects
			(font
				(size 1.27 1.27)
			)
			(justify left bottom)
		)
	)
	(label "B.DQS9_P"
		(at 130.81 158.75 0)
		(effects
			(font
				(size 1.27 1.27)
			)
			(justify left bottom)
		)
	)
	(label "SD.CMD"
		(at 314.96 93.98 0)
		(effects
			(font
				(size 1.27 1.27)
			)
			(justify left bottom)
		)
	)
	(label "CTRL.CK_P"
		(at 95.25 36.83 180)
		(effects
			(font
				(size 1.27 1.27)
			)
			(justify right bottom)
		)
	)
	(label "VRP_65"
		(at 130.81 90.17 0)
		(effects
			(font
				(size 1.27 1.27)
			)
			(justify left bottom)
		)
	)
	(label "CTRL.~{RESET}"
		(at 95.25 31.75 180)
		(effects
			(font
				(size 1.27 1.27)
			)
			(justify right bottom)
		)
	)
	(label "A.DQ27"
		(at 41.91 71.12 0)
		(effects
			(font
				(size 1.27 1.27)
			)
			(justify left bottom)
		)
	)
	(label "B.DQS4_N"
		(at 130.81 176.53 0)
		(effects
			(font
				(size 1.27 1.27)
			)
			(justify left bottom)
		)
	)
	(label "A.DQ12"
		(at 41.91 152.4 0)
		(effects
			(font
				(size 1.27 1.27)
			)
			(justify left bottom)
		)
	)
	(label "GCLK_100_LVDS-"
		(at 384.81 238.76 180)
		(effects
			(font
				(size 1.27 1.27)
			)
			(justify right bottom)
		)
	)
	(label "B.DQS6_P"
		(at 233.68 107.95 0)
		(effects
			(font
				(size 1.27 1.27)
			)
			(justify left bottom)
		)
	)
	(label "B.DQ15"
		(at 233.68 113.03 0)
		(effects
			(font
				(size 1.27 1.27)
			)
			(justify left bottom)
		)
	)
	(label "A.DQS0_P"
		(at 41.91 157.48 0)
		(effects
			(font
				(size 1.27 1.27)
			)
			(justify left bottom)
		)
	)
	(label "VRP_64"
		(at 41.91 88.9 0)
		(effects
			(font
				(size 1.27 1.27)
			)
			(justify left bottom)
		)
	)
	(label "B.DQ21"
		(at 233.68 153.67 0)
		(effects
			(font
				(size 1.27 1.27)
			)
			(justify left bottom)
		)
	)
	(label "B.DQ16"
		(at 233.68 130.81 0)
		(effects
			(font
				(size 1.27 1.27)
			)
			(justify left bottom)
		)
	)
	(label "A.DQS8_N"
		(at 41.91 76.2 0)
		(effects
			(font
				(size 1.27 1.27)
			)
			(justify left bottom)
		)
	)
	(label "VREF_65"
		(at 104.14 242.57 0)
		(effects
			(font
				(size 1.27 1.27)
			)
			(justify left bottom)
		)
	)
	(label "A.DQS7_N"
		(at 41.91 109.22 0)
		(effects
			(font
				(size 1.27 1.27)
			)
			(justify left bottom)
		)
	)
	(label "HyperRAM.RWDS"
		(at 317.5 58.42 0)
		(effects
			(font
				(size 1.27 1.27)
			)
			(justify left bottom)
		)
	)
	(label "VRP_64"
		(at 222.25 240.03 0)
		(effects
			(font
				(size 1.27 1.27)
			)
			(justify left bottom)
		)
	)
	(label "SD.DAT1"
		(at 314.96 104.14 0)
		(effects
			(font
				(size 1.27 1.27)
			)
			(justify left bottom)
		)
	)
	(label "A.CB0"
		(at 130.81 67.31 0)
		(effects
			(font
				(size 1.27 1.27)
			)
			(justify left bottom)
		)
	)
	(label "VREF_66"
		(at 233.68 54.61 0)
		(effects
			(font
				(size 1.27 1.27)
			)
			(justify left bottom)
		)
	)
	(label "SD.DAT0"
		(at 314.96 101.6 0)
		(effects
			(font
				(size 1.27 1.27)
			)
			(justify left bottom)
		)
	)
	(label "A.CA3"
		(at 130.81 105.41 0)
		(effects
			(font
				(size 1.27 1.27)
			)
			(justify left bottom)
		)
	)
	(label "HyperRAM.~{CS}"
		(at 317.5 91.44 0)
		(effects
			(font
				(size 1.27 1.27)
			)
			(justify left bottom)
		)
	)
	(label "A.CB5"
		(at 130.81 87.63 0)
		(effects
			(font
				(size 1.27 1.27)
			)
			(justify left bottom)
		)
	)
	(label "A.CA2"
		(at 130.81 102.87 0)
		(effects
			(font
				(size 1.27 1.27)
			)
			(justify left bottom)
		)
	)
	(label "A.DQ28"
		(at 41.91 78.74 0)
		(effects
			(font
				(size 1.27 1.27)
			)
			(justify left bottom)
		)
	)
	(label "B.CB5"
		(at 130.81 171.45 0)
		(effects
			(font
				(size 1.27 1.27)
			)
			(justify left bottom)
		)
	)
	(label "VREF_67"
		(at 335.28 53.34 0)
		(effects
			(font
				(size 1.27 1.27)
			)
			(justify left bottom)
		)
	)
	(label "A.DQ22"
		(at 41.91 116.84 0)
		(effects
			(font
				(size 1.27 1.27)
			)
			(justify left bottom)
		)
	)
	(label "ETH.RXD3"
		(at 317.5 147.32 0)
		(effects
			(font
				(size 1.27 1.27)
			)
			(justify left bottom)
		)
	)
	(label "A.DQ20"
		(at 41.91 111.76 0)
		(effects
			(font
				(size 1.27 1.27)
			)
			(justify left bottom)
		)
	)
	(label "ETH.TXC"
		(at 317.5 162.56 0)
		(effects
			(font
				(size 1.27 1.27)
			)
			(justify left bottom)
		)
	)
	(label "B.CS1_c"
		(at 130.81 128.27 0)
		(effects
			(font
				(size 1.27 1.27)
			)
			(justify left bottom)
		)
	)
	(label "A.DQS3_P"
		(at 41.91 58.42 0)
		(effects
			(font
				(size 1.27 1.27)
			)
			(justify left bottom)
		)
	)
	(label "A.DQ18"
		(at 41.91 101.6 0)
		(effects
			(font
				(size 1.27 1.27)
			)
			(justify left bottom)
		)
	)
	(label "B.DQ18"
		(at 233.68 133.35 0)
		(effects
			(font
				(size 1.27 1.27)
			)
			(justify left bottom)
		)
	)
	(label "B.DQ23"
		(at 233.68 151.13 0)
		(effects
			(font
				(size 1.27 1.27)
			)
			(justify left bottom)
		)
	)
	(label "ETH.MDIO"
		(at 317.5 177.8 0)
		(effects
			(font
				(size 1.27 1.27)
			)
			(justify left bottom)
		)
	)
	(label "A.CB6"
		(at 130.81 80.01 0)
		(effects
			(font
				(size 1.27 1.27)
			)
			(justify left bottom)
		)
	)
	(label "A.DQ16"
		(at 41.91 96.52 0)
		(effects
			(font
				(size 1.27 1.27)
			)
			(justify left bottom)
		)
	)
	(label "GCLK_100_LVDS-"
		(at 325.12 132.08 0)
		(effects
			(font
				(size 1.27 1.27)
			)
			(justify left bottom)
		)
	)
	(label "A.DQ25"
		(at 41.91 68.58 0)
		(effects
			(font
				(size 1.27 1.27)
			)
			(justify left bottom)
		)
	)
	(label "B.DQS8_N"
		(at 233.68 176.53 0)
		(effects
			(font
				(size 1.27 1.27)
			)
			(justify left bottom)
		)
	)
	(label "B.DQS7_P"
		(at 233.68 140.97 0)
		(effects
			(font
				(size 1.27 1.27)
			)
			(justify left bottom)
		)
	)
	(label "B.DQS0_P"
		(at 233.68 59.69 0)
		(effects
			(font
				(size 1.27 1.27)
			)
			(justify left bottom)
		)
	)
	(label "A.DQ2"
		(at 41.91 165.1 0)
		(effects
			(font
				(size 1.27 1.27)
			)
			(justify left bottom)
		)
	)
	(label "B.DQ4"
		(at 233.68 80.01 0)
		(effects
			(font
				(size 1.27 1.27)
			)
			(justify left bottom)
		)
	)
	(global_label "HDMI_REC_CLK_N"
		(shape output)
		(at 325.12 119.38 180)
		(fields_autoplaced yes)
		(effects
			(font
				(size 1.27 1.27)
			)
			(justify right)
		)
		(property "Intersheetrefs" "${INTERSHEET_REFS}"
			(at 306.6419 119.38 0)
			(effects
				(font
					(size 1.27 1.27)
				)
				(justify right)
			)
		)
	)
	(global_label "DAC_VREF"
		(shape input)
		(at 73.66 227.33 180)
		(effects
			(font
				(size 1.27 1.27)
			)
			(justify right)
		)
		(property "Intersheetrefs" "${INTERSHEET_REFS}"
			(at 63.5 227.33 0)
			(effects
				(font
					(size 1.27 1.27)
				)
				(justify right)
			)
		)
	)
	(global_label "HDMI_REC_CLK_P"
		(shape output)
		(at 325.12 116.84 180)
		(fields_autoplaced yes)
		(effects
			(font
				(size 1.27 1.27)
			)
			(justify right)
		)
		(property "Intersheetrefs" "${INTERSHEET_REFS}"
			(at 306.7024 116.84 0)
			(effects
				(font
					(size 1.27 1.27)
				)
				(justify right)
			)
		)
	)
	(hierarchical_label "SD{SDIO}"
		(shape bidirectional)
		(at 308.61 86.36 180)
		(effects
			(font
				(size 1.27 1.27)
			)
			(justify right)
		)
	)
	(hierarchical_label "A{DDR5_RDIMM}"
		(shape input)
		(at 31.75 45.72 180)
		(effects
			(font
				(size 1.27 1.27)
			)
			(justify right)
		)
	)
	(hierarchical_label "ETH{RGMII}"
		(shape bidirectional)
		(at 312.42 130.81 180)
		(effects
			(font
				(size 1.27 1.27)
			)
			(justify right)
		)
	)
	(hierarchical_label "A{DDR5_RDIMM}"
		(shape input)
		(at 120.65 46.99 180)
		(effects
			(font
				(size 1.27 1.27)
			)
			(justify right)
		)
	)
	(hierarchical_label "CTRL{DDR5_RDIMM}"
		(shape input)
		(at 66.04 16.51 180)
		(effects
			(font
				(size 1.27 1.27)
			)
			(justify right)
		)
	)
	(hierarchical_label "B{DDR5_RDIMM}"
		(shape input)
		(at 223.52 44.45 180)
		(effects
			(font
				(size 1.27 1.27)
			)
			(justify right)
		)
	)
	(hierarchical_label "B{DDR5_RDIMM}"
		(shape input)
		(at 120.65 119.38 180)
		(effects
			(font
				(size 1.27 1.27)
			)
			(justify right)
		)
	)
	(hierarchical_label "HyperRAM{HyperBus}"
		(shape bidirectional)
		(at 313.69 54.61 180)
		(effects
			(font
				(size 1.27 1.27)
			)
			(justify right)
		)
	)
	(symbol
		(lib_id "antmicropower:GND")
		(at 240.03 242.57 0)
		(mirror y)
		(unit 1)
		(exclude_from_sim no)
		(in_bom yes)
		(on_board yes)
		(dnp no)
		(fields_autoplaced yes)
		(property "Reference" "#PWR0281"
			(at 240.03 248.92 0)
			(effects
				(font
					(size 1.27 1.27)
				)
				(hide yes)
			)
		)
		(property "Value" "GND"
			(at 241.935 247.015 0)
			(effects
				(font
					(size 1.27 1.27)
					(thickness 0.15)
				)
				(justify left bottom)
			)
		)
		(property "Footprint" ""
			(at 231.14 250.19 0)
			(effects
				(font
					(size 1.27 1.27)
					(thickness 0.15)
				)
				(justify left bottom)
				(hide yes)
			)
		)
		(property "Datasheet" ""
			(at 231.14 255.27 0)
			(effects
				(font
					(size 1.27 1.27)
					(thickness 0.15)
				)
				(justify left bottom)
				(hide yes)
			)
		)
		(property "Description" ""
			(at 240.03 242.57 0)
			(effects
				(font
					(size 1.27 1.27)
				)
				(hide yes)
			)
		)
		(property "Author" "Antmicro"
			(at 231.14 247.65 0)
			(effects
				(font
					(size 1.27 1.27)
					(thickness 0.15)
				)
				(justify left bottom)
				(hide yes)
			)
		)
		(property "License" "Apache-2.0"
			(at 231.14 250.19 0)
			(effects
				(font
					(size 1.27 1.27)
					(thickness 0.15)
				)
				(justify left bottom)
				(hide yes)
			)
		)
		(pin "1"
		)
		(instances
			(project "data-center-rdimm-ddr5-tester"
				(path ""
					(reference "#PWR0281")
					(unit 1)
				)
			)
		)
	)
	(symbol
		(lib_id "antmicroResistors0402:R_1k_0402")
		(at 134.62 248.92 90)
		(unit 1)
		(exclude_from_sim no)
		(in_bom no)
		(on_board yes)
		(dnp yes)
		(property "Reference" "R131"
			(at 135.89 245.11 90)
			(effects
				(font
					(size 1.27 1.27)
					(thickness 0.15)
				)
				(justify right)
			)
		)
		(property "Value" "R_1k_0402"
			(at 147.32 228.6 0)
			(effects
				(font
					(size 1.27 1.27)
					(thickness 0.15)
				)
				(justify left bottom)
				(hide yes)
			)
		)
		(property "Footprint" "antmicro-footprints:R_0402_1005Metric_EIA"
			(at 149.86 228.6 0)
			(effects
				(font
					(size 1.27 1.27)
					(thickness 0.15)
				)
				(justify left bottom)
				(hide yes)
			)
		)
		(property "Datasheet" "https://www.bourns.com/docs/product-datasheets/cr.pdf"
			(at 152.4 228.6 0)
			(effects
				(font
					(size 1.27 1.27)
					(thickness 0.15)
				)
				(justify left bottom)
				(hide yes)
			)
		)
		(property "Description" ""
			(at 134.62 248.92 0)
			(effects
				(font
					(size 1.27 1.27)
				)
				(hide yes)
			)
		)
		(property "MPN" "CR0402-FX-1001GLF"
			(at 154.94 228.6 0)
			(effects
				(font
					(size 1.27 1.27)
					(thickness 0.15)
				)
				(justify left bottom)
				(hide yes)
			)
		)
		(property "Manufacturer" "Bourns"
			(at 157.48 228.6 0)
			(effects
				(font
					(size 1.27 1.27)
					(thickness 0.15)
				)
				(justify left bottom)
				(hide yes)
			)
		)
		(property "License" "Apache-2.0"
			(at 160.02 228.6 0)
			(effects
				(font
					(size 1.27 1.27)
					(thickness 0.15)
				)
				(justify left bottom)
				(hide yes)
			)
		)
		(property "Author" "Antmicro"
			(at 162.56 228.6 0)
			(effects
				(font
					(size 1.27 1.27)
					(thickness 0.15)
				)
				(justify left bottom)
				(hide yes)
			)
		)
		(property "Val" "1k"
			(at 135.89 247.65 90)
			(effects
				(font
					(size 1.27 1.27)
					(thickness 0.15)
				)
				(justify right)
			)
		)
		(property "Tolerance" "1%"
			(at 144.78 228.6 0)
			(effects
				(font
					(size 1.27 1.27)
				)
				(justify left bottom)
				(hide yes)
			)
		)
		(pin "2"
		)
		(pin "1"
		)
		(instances
			(project "data-center-rdimm-ddr5-tester"
				(path ""
					(reference "R131")
					(unit 1)
				)
			)
		)
	)
	(symbol
		(lib_name "XCAU25P-2FFVB676I_1")
		(lib_id "antmicroFPGAChips:XCAU25P-2FFVB676I")
		(at 52.07 50.8 0)
		(unit 2)
		(exclude_from_sim no)
		(in_bom yes)
		(on_board yes)
		(dnp no)
		(property "Reference" "U34"
			(at 57.15 44.45 0)
			(effects
				(font
					(size 1.27 1.27)
					(thickness 0.15)
				)
				(justify left)
			)
		)
		(property "Value" "XCAU25P-2FFVB676I"
			(at 115.57 55.88 0)
			(effects
				(font
					(size 1.27 1.27)
					(thickness 0.15)
				)
				(justify left bottom)
				(hide yes)
			)
		)
		(property "Footprint" "antmicro-footprints:BGA-676_27x27mm_Layout26x26_P1x1mm_FFVB676"
			(at 115.57 58.42 0)
			(effects
				(font
					(size 1.27 1.27)
					(thickness 0.15)
				)
				(justify left bottom)
				(hide yes)
			)
		)
		(property "Datasheet" "https://docs.xilinx.com/viewer/book-attachment/2PXOpPtpaABIt0fkzeBLnw/hvbsEUaOT0OxFhln7VEVyA"
			(at 115.57 60.96 0)
			(effects
				(font
					(size 1.27 1.27)
					(thickness 0.15)
				)
				(justify left bottom)
				(hide yes)
			)
		)
		(property "Description" ""
			(at 52.07 50.8 0)
			(effects
				(font
					(size 1.27 1.27)
				)
				(hide yes)
			)
		)
		(property "MPN" "XCAU25P-2FFVB676I"
			(at 57.15 46.99 0)
			(effects
				(font
					(size 1.27 1.27)
					(thickness 0.15)
				)
				(justify left)
			)
		)
		(property "Manufacturer" "AMD-Xilinx"
			(at 115.57 63.5 0)
			(effects
				(font
					(size 1.27 1.27)
					(thickness 0.15)
				)
				(justify left bottom)
				(hide yes)
			)
		)
		(property "Author" "Antmicro"
			(at 115.57 66.04 0)
			(effects
				(font
					(size 1.27 1.27)
					(thickness 0.15)
				)
				(justify left bottom)
				(hide yes)
			)
		)
		(property "License" "Apache-2.0"
			(at 115.57 68.58 0)
			(effects
				(font
					(size 1.27 1.27)
					(thickness 0.15)
				)
				(justify left bottom)
				(hide yes)
			)
		)
		(pin "AC23"
		)
		(pin "P20"
		)
		(pin "N19"
		)
		(pin "AA24"
		)
		(pin "J16"
		)
		(pin "J21"
		)
		(pin "AE10"
		)
		(pin "F6"
		)
		(pin "F7"
		)
		(pin "AF17"
		)
		(pin "AA15"
		)
		(pin "J25"
		)
		(pin "Y21"
		)
		(pin "AA7"
		)
		(pin "E26"
		)
		(pin "AD16"
		)
		(pin "V1"
		)
		(pin "AB14"
		)
		(pin "Y1"
		)
		(pin "E24"
		)
		(pin "AA14"
		)
		(pin "J20"
		)
		(pin "U25"
		)
		(pin "AE18"
		)
		(pin "U22"
		)
		(pin "P4"
		)
		(pin "P5"
		)
		(pin "R1"
		)
		(pin "R10"
		)
		(pin "P8"
		)
		(pin "P9"
		)
		(pin "R11"
		)
		(pin "R12"
		)
		(pin "AD3"
		)
		(pin "AD9"
		)
		(pin "AD4"
		)
		(pin "P18"
		)
		(pin "P3"
		)
		(pin "G14"
		)
		(pin "AE26"
		)
		(pin "B12"
		)
		(pin "AC2"
		)
		(pin "W7"
		)
		(pin "W8"
		)
		(pin "W11"
		)
		(pin "W17"
		)
		(pin "W2"
		)
		(pin "W22"
		)
		(pin "W3"
		)
		(pin "W6"
		)
		(pin "P6"
		)
		(pin "U26"
		)
		(pin "P19"
		)
		(pin "U1"
		)
		(pin "U10"
		)
		(pin "J15"
		)
		(pin "AB25"
		)
		(pin "L23"
		)
		(pin "P24"
		)
		(pin "G16"
		)
		(pin "C10"
		)
		(pin "F14"
		)
		(pin "U24"
		)
		(pin "Y24"
		)
		(pin "Y11"
		)
		(pin "J26"
		)
		(pin "AB4"
		)
		(pin "AD18"
		)
		(pin "J24"
		)
		(pin "AF2"
		)
		(pin "B26"
		)
		(pin "U6"
		)
		(pin "U7"
		)
		(pin "M11"
		)
		(pin "M12"
		)
		(pin "T20"
		)
		(pin "V23"
		)
		(pin "AD10"
		)
		(pin "D1"
		)
		(pin "AF1"
		)
		(pin "C8"
		)
		(pin "U13"
		)
		(pin "U14"
		)
		(pin "AD19"
		)
		(pin "Y4"
		)
		(pin "Y5"
		)
		(pin "E23"
		)
		(pin "C6"
		)
		(pin "AE14"
		)
		(pin "D22"
		)
		(pin "C20"
		)
		(pin "AB17"
		)
		(pin "AD24"
		)
		(pin "L1"
		)
		(pin "L10"
		)
		(pin "AE3"
		)
		(pin "G21"
		)
		(pin "AA17"
		)
		(pin "D6"
		)
		(pin "M25"
		)
		(pin "R17"
		)
		(pin "R18"
		)
		(pin "AE15"
		)
		(pin "H7"
		)
		(pin "H8"
		)
		(pin "R6"
		)
		(pin "R7"
		)
		(pin "AB20"
		)
		(pin "C5"
		)
		(pin "Y14"
		)
		(pin "AE13"
		)
		(pin "C13"
		)
		(pin "W4"
		)
		(pin "P22"
		)
		(pin "AF6"
		)
		(pin "B8"
		)
		(pin "AF18"
		)
		(pin "G22"
		)
		(pin "J2"
		)
		(pin "J3"
		)
		(pin "L3"
		)
		(pin "L6"
		)
		(pin "P12"
		)
		(pin "P15"
		)
		(pin "Y12"
		)
		(pin "K18"
		)
		(pin "V10"
		)
		(pin "V11"
		)
		(pin "D7"
		)
		(pin "D8"
		)
		(pin "P23"
		)
		(pin "AA3"
		)
		(pin "AB18"
		)
		(pin "H18"
		)
		(pin "B6"
		)
		(pin "R24"
		)
		(pin "R3"
		)
		(pin "P16"
		)
		(pin "P17"
		)
		(pin "AF23"
		)
		(pin "AC14"
		)
		(pin "M6"
		)
		(pin "B18"
		)
		(pin "M1"
		)
		(pin "B5"
		)
		(pin "D2"
		)
		(pin "G20"
		)
		(pin "M2"
		)
		(pin "B4"
		)
		(pin "AA16"
		)
		(pin "V9"
		)
		(pin "W1"
		)
		(pin "N5"
		)
		(pin "AA26"
		)
		(pin "B3"
		)
		(pin "D12"
		)
		(pin "N4"
		)
		(pin "AA2"
		)
		(pin "B23"
		)
		(pin "C12"
		)
		(pin "L5"
		)
		(pin "AA6"
		)
		(pin "B1"
		)
		(pin "H1"
		)
		(pin "A14"
		)
		(pin "A13"
		)
		(pin "AB2"
		)
		(pin "AE4"
		)
		(pin "Y16"
		)
		(pin "B24"
		)
		(pin "H16"
		)
		(pin "W24"
		)
		(pin "D18"
		)
		(pin "B20"
		)
		(pin "D21"
		)
		(pin "B19"
		)
		(pin "B25"
		)
		(pin "C24"
		)
		(pin "A15"
		)
		(pin "M26"
		)
		(pin "A23"
		)
		(pin "C17"
		)
		(pin "K21"
		)
		(pin "W23"
		)
		(pin "L24"
		)
		(pin "R20"
		)
		(pin "C21"
		)
		(pin "D24"
		)
		(pin "E15"
		)
		(pin "AD12"
		)
		(pin "D23"
		)
		(pin "D25"
		)
		(pin "C26"
		)
		(pin "B21"
		)
		(pin "Y26"
		)
		(pin "AE25"
		)
		(pin "C19"
		)
		(pin "C23"
		)
		(pin "P21"
		)
		(pin "A20"
		)
		(pin "L18"
		)
		(pin "A25"
		)
		(pin "K23"
		)
		(pin "V18"
		)
		(pin "C16"
		)
		(pin "V21"
		)
		(pin "E17"
		)
		(pin "A17"
		)
		(pin "P25"
		)
		(pin "AD25"
		)
		(pin "G18"
		)
		(pin "AB3"
		)
		(pin "J6"
		)
		(pin "J7"
		)
		(pin "K12"
		)
		(pin "K13"
		)
		(pin "AB16"
		)
		(pin "C1"
		)
		(pin "AF15"
		)
		(pin "J8"
		)
		(pin "K11"
		)
		(pin "AD1"
		)
		(pin "F25"
		)
		(pin "AE1"
		)
		(pin "V2"
		)
		(pin "U2"
		)
		(pin "U3"
		)
		(pin "F2"
		)
		(pin "V6"
		)
		(pin "P1"
		)
		(pin "L13"
		)
		(pin "L14"
		)
		(pin "AD5"
		)
		(pin "AE8"
		)
		(pin "AB10"
		)
		(pin "U15"
		)
		(pin "U16"
		)
		(pin "U17"
		)
		(pin "U18"
		)
		(pin "D26"
		)
		(pin "G5"
		)
		(pin "E25"
		)
		(pin "AD22"
		)
		(pin "A19"
		)
		(pin "P7"
		)
		(pin "Y2"
		)
		(pin "J22"
		)
		(pin "Y19"
		)
		(pin "Y3"
		)
		(pin "AB7"
		)
		(pin "AF22"
		)
		(pin "B2"
		)
		(pin "AA10"
		)
		(pin "V7"
		)
		(pin "V22"
		)
		(pin "J23"
		)
		(pin "AF12"
		)
		(pin "V16"
		)
		(pin "V17"
		)
		(pin "Y7"
		)
		(pin "D15"
		)
		(pin "H12"
		)
		(pin "AF7"
		)
		(pin "U23"
		)
		(pin "V19"
		)
		(pin "AF14"
		)
		(pin "AF13"
		)
		(pin "G8"
		)
		(pin "H20"
		)
		(pin "U11"
		)
		(pin "U12"
		)
		(pin "A5"
		)
		(pin "G6"
		)
		(pin "G7"
		)
		(pin "L15"
		)
		(pin "L16"
		)
		(pin "T8"
		)
		(pin "T9"
		)
		(pin "G19"
		)
		(pin "G17"
		)
		(pin "T4"
		)
		(pin "T5"
		)
		(pin "B13"
		)
		(pin "G23"
		)
		(pin "G3"
		)
		(pin "T26"
		)
		(pin "T3"
		)
		(pin "G13"
		)
		(pin "G2"
		)
		(pin "D17"
		)
		(pin "AD15"
		)
		(pin "Y8"
		)
		(pin "Y9"
		)
		(pin "AC24"
		)
		(pin "AD8"
		)
		(pin "F8"
		)
		(pin "G1"
		)
		(pin "AD6"
		)
		(pin "F18"
		)
		(pin "H17"
		)
		(pin "AA13"
		)
		(pin "K20"
		)
		(pin "AD7"
		)
		(pin "AA1"
		)
		(pin "AF19"
		)
		(pin "Y15"
		)
		(pin "AB13"
		)
		(pin "N13"
		)
		(pin "N14"
		)
		(pin "V14"
		)
		(pin "V15"
		)
		(pin "U8"
		)
		(pin "U9"
		)
		(pin "W13"
		)
		(pin "V5"
		)
		(pin "V8"
		)
		(pin "W5"
		)
		(pin "P26"
		)
		(pin "Y20"
		)
		(pin "L17"
		)
		(pin "L2"
		)
		(pin "H26"
		)
		(pin "Y6"
		)
		(pin "AC22"
		)
		(pin "D13"
		)
		(pin "V12"
		)
		(pin "V13"
		)
		(pin "AE9"
		)
		(pin "B7"
		)
		(pin "A11"
		)
		(pin "K9"
		)
		(pin "L11"
		)
		(pin "L12"
		)
		(pin "H5"
		)
		(pin "H6"
		)
		(pin "AE19"
		)
		(pin "C18"
		)
		(pin "H13"
		)
		(pin "AB23"
		)
		(pin "AC26"
		)
		(pin "R19"
		)
		(pin "R2"
		)
		(pin "H19"
		)
		(pin "AF20"
		)
		(pin "AF24"
		)
		(pin "B22"
		)
		(pin "B14"
		)
		(pin "D4"
		)
		(pin "AA18"
		)
		(pin "C22"
		)
		(pin "V24"
		)
		(pin "A12"
		)
		(pin "C7"
		)
		(pin "M7"
		)
		(pin "AB5"
		)
		(pin "W18"
		)
		(pin "T18"
		)
		(pin "T21"
		)
		(pin "F13"
		)
		(pin "D3"
		)
		(pin "F1"
		)
		(pin "L21"
		)
		(pin "L26"
		)
		(pin "AA11"
		)
		(pin "M20"
		)
		(pin "AC4"
		)
		(pin "AE5"
		)
		(pin "D19"
		)
		(pin "E10"
		)
		(pin "AA9"
		)
		(pin "Y22"
		)
		(pin "V3"
		)
		(pin "V4"
		)
		(pin "AD2"
		)
		(pin "AC10"
		)
		(pin "C25"
		)
		(pin "G4"
		)
		(pin "A6"
		)
		(pin "E6"
		)
		(pin "E7"
		)
		(pin "E1"
		)
		(pin "E19"
		)
		(pin "R4"
		)
		(pin "T10"
		)
		(pin "T11"
		)
		(pin "J10"
		)
		(pin "F17"
		)
		(pin "A24"
		)
		(pin "AC15"
		)
		(pin "C15"
		)
		(pin "A1"
		)
		(pin "J1"
		)
		(pin "J17"
		)
		(pin "AE6"
		)
		(pin "E4"
		)
		(pin "E5"
		)
		(pin "M23"
		)
		(pin "M3"
		)
		(pin "R22"
		)
		(pin "AA5"
		)
		(pin "AC12"
		)
		(pin "Y18"
		)
		(pin "W20"
		)
		(pin "AC21"
		)
		(pin "R23"
		)
		(pin "K10"
		)
		(pin "AC17"
		)
		(pin "AC20"
		)
		(pin "V20"
		)
		(pin "V25"
		)
		(pin "N1"
		)
		(pin "N10"
		)
		(pin "M4"
		)
		(pin "M5"
		)
		(pin "R25"
		)
		(pin "H3"
		)
		(pin "H4"
		)
		(pin "AD13"
		)
		(pin "AD17"
		)
		(pin "N26"
		)
		(pin "R13"
		)
		(pin "N6"
		)
		(pin "N7"
		)
		(pin "U4"
		)
		(pin "R5"
		)
		(pin "K3"
		)
		(pin "K4"
		)
		(pin "AF3"
		)
		(pin "J5"
		)
		(pin "P2"
		)
		(pin "N22"
		)
		(pin "T16"
		)
		(pin "T17"
		)
		(pin "C3"
		)
		(pin "AF4"
		)
		(pin "T13"
		)
		(pin "AA12"
		)
		(pin "AB26"
		)
		(pin "AF21"
		)
		(pin "N25"
		)
		(pin "N3"
		)
		(pin "N21"
		)
		(pin "J12"
		)
		(pin "A8"
		)
		(pin "W12"
		)
		(pin "H14"
		)
		(pin "U21"
		)
		(pin "W9"
		)
		(pin "T14"
		)
		(pin "AE23"
		)
		(pin "K19"
		)
		(pin "K24"
		)
		(pin "Y25"
		)
		(pin "G12"
		)
		(pin "N2"
		)
		(pin "N20"
		)
		(pin "T25"
		)
		(pin "AC8"
		)
		(pin "E16"
		)
		(pin "AC19"
		)
		(pin "C14"
		)
		(pin "F4"
		)
		(pin "F5"
		)
		(pin "U19"
		)
		(pin "AE12"
		)
		(pin "P14"
		)
		(pin "AF8"
		)
		(pin "AF9"
		)
		(pin "V26"
		)
		(pin "W19"
		)
		(pin "L4"
		)
		(pin "G24"
		)
		(pin "R15"
		)
		(pin "R16"
		)
		(pin "U5"
		)
		(pin "AC16"
		)
		(pin "AF25"
		)
		(pin "T7"
		)
		(pin "F24"
		)
		(pin "D16"
		)
		(pin "AA19"
		)
		(pin "D5"
		)
		(pin "L22"
		)
		(pin "B17"
		)
		(pin "H15"
		)
		(pin "AE21"
		)
		(pin "AE7"
		)
		(pin "K5"
		)
		(pin "K6"
		)
		(pin "T1"
		)
		(pin "AE22"
		)
		(pin "E22"
		)
		(pin "AF10"
		)
		(pin "AB6"
		)
		(pin "AD26"
		)
		(pin "AC13"
		)
		(pin "E18"
		)
		(pin "M15"
		)
		(pin "M16"
		)
		(pin "G15"
		)
		(pin "N8"
		)
		(pin "N9"
		)
		(pin "W26"
		)
		(pin "F20"
		)
		(pin "AD23"
		)
		(pin "AA8"
		)
		(pin "D20"
		)
		(pin "AF11"
		)
		(pin "E8"
		)
		(pin "F11"
		)
		(pin "AC5"
		)
		(pin "AA22"
		)
		(pin "E20"
		)
		(pin "W14"
		)
		(pin "M19"
		)
		(pin "H24"
		)
		(pin "K7"
		)
		(pin "K8"
		)
		(pin "C4"
		)
		(pin "H25"
		)
		(pin "W21"
		)
		(pin "P13"
		)
		(pin "L20"
		)
		(pin "AB21"
		)
		(pin "C2"
		)
		(pin "H22"
		)
		(pin "Y17"
		)
		(pin "AE11"
		)
		(pin "H2"
		)
		(pin "F23"
		)
		(pin "E11"
		)
		(pin "AB24"
		)
		(pin "AA4"
		)
		(pin "T6"
		)
		(pin "AD20"
		)
		(pin "A10"
		)
		(pin "C9"
		)
		(pin "W15"
		)
		(pin "E21"
		)
		(pin "AB22"
		)
		(pin "W16"
		)
		(pin "AC25"
		)
		(pin "T22"
		)
		(pin "K1"
		)
		(pin "AD14"
		)
		(pin "T2"
		)
		(pin "J19"
		)
		(pin "D9"
		)
		(pin "AE17"
		)
		(pin "AB1"
		)
		(pin "T24"
		)
		(pin "F9"
		)
		(pin "M8"
		)
		(pin "M9"
		)
		(pin "Y23"
		)
		(pin "AC7"
		)
		(pin "M13"
		)
		(pin "M14"
		)
		(pin "G25"
		)
		(pin "A9"
		)
		(pin "AB19"
		)
		(pin "A7"
		)
		(pin "N15"
		)
		(pin "N16"
		)
		(pin "Y13"
		)
		(pin "AF5"
		)
		(pin "R14"
		)
		(pin "AE20"
		)
		(pin "AB11"
		)
		(pin "W25"
		)
		(pin "T19"
		)
		(pin "H21"
		)
		(pin "K2"
		)
		(pin "T23"
		)
		(pin "AC6"
		)
		(pin "B15"
		)
		(pin "E9"
		)
		(pin "AC3"
		)
		(pin "F10"
		)
		(pin "A3"
		)
		(pin "F15"
		)
		(pin "U20"
		)
		(pin "G10"
		)
		(pin "N23"
		)
		(pin "AB15"
		)
		(pin "AA21"
		)
		(pin "P10"
		)
		(pin "P11"
		)
		(pin "J11"
		)
		(pin "Y10"
		)
		(pin "F19"
		)
		(pin "A22"
		)
		(pin "AE16"
		)
		(pin "F22"
		)
		(pin "G11"
		)
		(pin "K25"
		)
		(pin "B10"
		)
		(pin "AA20"
		)
		(pin "N24"
		)
		(pin "AA25"
		)
		(pin "E12"
		)
		(pin "D11"
		)
		(pin "E14"
		)
		(pin "AC1"
		)
		(pin "J4"
		)
		(pin "H11"
		)
		(pin "H9"
		)
		(pin "M22"
		)
		(pin "H10"
		)
		(pin "E13"
		)
		(pin "AD21"
		)
		(pin "D10"
		)
		(pin "B11"
		)
		(pin "G26"
		)
		(pin "L25"
		)
		(pin "AB9"
		)
		(pin "A2"
		)
		(pin "M21"
		)
		(pin "C11"
		)
		(pin "R21"
		)
		(pin "D14"
		)
		(pin "F12"
		)
		(pin "B9"
		)
		(pin "J9"
		)
		(pin "L19"
		)
		(pin "B16"
		)
		(pin "K22"
		)
		(pin "K26"
		)
		(pin "N11"
		)
		(pin "N12"
		)
		(pin "A16"
		)
		(pin "AB12"
		)
		(pin "L7"
		)
		(pin "L8"
		)
		(pin "AC11"
		)
		(pin "J18"
		)
		(pin "K16"
		)
		(pin "K17"
		)
		(pin "M24"
		)
		(pin "M17"
		)
		(pin "M18"
		)
		(pin "J14"
		)
		(pin "R8"
		)
		(pin "R9"
		)
		(pin "A26"
		)
		(pin "H23"
		)
		(pin "AF16"
		)
		(pin "F26"
		)
		(pin "F3"
		)
		(pin "AC18"
		)
		(pin "W10"
		)
		(pin "G9"
		)
		(pin "K14"
		)
		(pin "K15"
		)
		(pin "N17"
		)
		(pin "N18"
		)
		(pin "AC9"
		)
		(pin "J13"
		)
		(pin "AE24"
		)
		(pin "AA23"
		)
		(pin "E2"
		)
		(pin "E3"
		)
		(pin "AE2"
		)
		(pin "AF26"
		)
		(pin "A21"
		)
		(pin "L9"
		)
		(pin "M10"
		)
		(pin "F16"
		)
		(pin "F21"
		)
		(pin "R26"
		)
		(pin "T12"
		)
		(pin "T15"
		)
		(pin "AB8"
		)
		(pin "A18"
		)
		(pin "A4"
		)
		(pin "AD11"
		)
		(instances
			(project "data-center-rdimm-ddr5-tester"
				(path ""
					(reference "U34")
					(unit 2)
				)
			)
		)
	)
	(symbol
		(lib_id "antmicropower:+1V1")
		(at 52.07 49.53 0)
		(unit 1)
		(exclude_from_sim no)
		(in_bom yes)
		(on_board yes)
		(dnp no)
		(property "Reference" "#PWR0190"
			(at 52.07 53.34 0)
			(effects
				(font
					(size 1.27 1.27)
				)
				(hide yes)
			)
		)
		(property "Value" "VDDQ"
			(at 52.07 45.974 0)
			(effects
				(font
					(size 1.27 1.27)
				)
			)
		)
		(property "Footprint" ""
			(at 52.07 49.53 0)
			(effects
				(font
					(size 1.27 1.27)
				)
				(hide yes)
			)
		)
		(property "Datasheet" ""
			(at 52.07 49.53 0)
			(effects
				(font
					(size 1.27 1.27)
				)
				(hide yes)
			)
		)
		(property "Description" ""
			(at 52.07 49.53 0)
			(effects
				(font
					(size 1.27 1.27)
				)
				(hide yes)
			)
		)
		(pin "1"
		)
		(instances
			(project "data-center-rdimm-ddr5-tester"
				(path ""
					(reference "#PWR0190")
					(unit 1)
				)
			)
		)
	)
	(symbol
		(lib_id "antmicroCapacitors0402:C_100n_0402")
		(at 144.78 243.84 90)
		(mirror x)
		(unit 1)
		(exclude_from_sim no)
		(in_bom yes)
		(on_board yes)
		(dnp no)
		(property "Reference" "C336"
			(at 145.415 244.475 90)
			(effects
				(font
					(size 1.27 1.27)
				)
				(justify right)
			)
		)
		(property "Value" "C_100n_0402"
			(at 154.94 264.16 0)
			(effects
				(font
					(size 1.27 1.27)
					(thickness 0.15)
				)
				(justify left bottom)
				(hide yes)
			)
		)
		(property "Footprint" "antmicro-footprints:C_0402_1005Metric"
			(at 157.48 264.16 0)
			(effects
				(font
					(size 1.27 1.27)
					(thickness 0.15)
				)
				(justify left bottom)
				(hide yes)
			)
		)
		(property "Datasheet" "https://www.murata.com/products/productdetail?partno=GRM155R61H104KE14%23"
			(at 160.02 264.16 0)
			(effects
				(font
					(size 1.27 1.27)
					(thickness 0.15)
				)
				(justify left bottom)
				(hide yes)
			)
		)
		(property "Description" ""
			(at 144.78 243.84 0)
			(effects
				(font
					(size 1.27 1.27)
				)
			)
		)
		(property "Manufacturer" "Murata"
			(at 165.1 264.16 0)
			(effects
				(font
					(size 1.27 1.27)
					(thickness 0.15)
				)
				(justify left bottom)
				(hide yes)
			)
		)
		(property "MPN" "GRM155R61H104KE14D"
			(at 162.56 264.16 0)
			(effects
				(font
					(size 1.27 1.27)
					(thickness 0.15)
				)
				(justify left bottom)
				(hide yes)
			)
		)
		(property "Val" "100n"
			(at 145.415 248.285 90)
			(effects
				(font
					(size 1.27 1.27)
					(thickness 0.15)
				)
				(justify right)
			)
		)
		(property "License" "Apache-2.0"
			(at 167.64 264.16 0)
			(effects
				(font
					(size 1.27 1.27)
					(thickness 0.15)
				)
				(justify left bottom)
				(hide yes)
			)
		)
		(property "Author" "Antmicro"
			(at 170.18 264.16 0)
			(effects
				(font
					(size 1.27 1.27)
					(thickness 0.15)
				)
				(justify left bottom)
				(hide yes)
			)
		)
		(property "Voltage" "50V"
			(at 172.72 264.16 0)
			(effects
				(font
					(size 1.27 1.27)
				)
				(justify left bottom)
				(hide yes)
			)
		)
		(property "Dielectric" "X5R"
			(at 175.26 264.16 0)
			(effects
				(font
					(size 1.27 1.27)
				)
				(justify left bottom)
				(hide yes)
			)
		)
		(pin "1"
		)
		(pin "2"
		)
		(instances
			(project "data-center-rdimm-ddr5-tester"
				(path ""
					(reference "C336")
					(unit 1)
				)
			)
		)
	)
	(symbol
		(lib_id "antmicropower:GND")
		(at 124.46 250.19 0)
		(mirror y)
		(unit 1)
		(exclude_from_sim no)
		(in_bom yes)
		(on_board yes)
		(dnp no)
		(property "Reference" "#PWR0560"
			(at 124.46 256.54 0)
			(effects
				(font
					(size 1.27 1.27)
				)
				(hide yes)
			)
		)
		(property "Value" "GND"
			(at 124.46 253.746 0)
			(effects
				(font
					(size 1.27 1.27)
					(thickness 0.15)
				)
			)
		)
		(property "Footprint" ""
			(at 115.57 257.81 0)
			(effects
				(font
					(size 1.27 1.27)
					(thickness 0.15)
				)
				(justify left bottom)
				(hide yes)
			)
		)
		(property "Datasheet" ""
			(at 115.57 262.89 0)
			(effects
				(font
					(size 1.27 1.27)
					(thickness 0.15)
				)
				(justify left bottom)
				(hide yes)
			)
		)
		(property "Description" ""
			(at 115.57 265.43 0)
			(effects
				(font
					(size 1.27 1.27)
				)
				(justify left bottom)
				(hide yes)
			)
		)
		(property "Author" "Antmicro"
			(at 115.57 257.81 0)
			(effects
				(font
					(size 1.27 1.27)
					(thickness 0.15)
				)
				(justify left bottom)
				(hide yes)
			)
		)
		(property "License" "Apache-2.0"
			(at 115.57 260.35 0)
			(effects
				(font
					(size 1.27 1.27)
					(thickness 0.15)
				)
				(justify left bottom)
				(hide yes)
			)
		)
		(pin "1"
		)
		(instances
			(project "data-center-rdimm-ddr5-tester"
				(path ""
					(reference "#PWR0560")
					(unit 1)
				)
			)
		)
	)
	(symbol
		(lib_id "antmicroCapacitors0402:C_100n_0402")
		(at 124.46 243.84 90)
		(mirror x)
		(unit 1)
		(exclude_from_sim no)
		(in_bom yes)
		(on_board yes)
		(dnp no)
		(property "Reference" "C335"
			(at 125.095 244.475 90)
			(effects
				(font
					(size 1.27 1.27)
				)
				(justify right)
			)
		)
		(property "Value" "C_100n_0402"
			(at 134.62 264.16 0)
			(effects
				(font
					(size 1.27 1.27)
					(thickness 0.15)
				)
				(justify left bottom)
				(hide yes)
			)
		)
		(property "Footprint" "antmicro-footprints:C_0402_1005Metric"
			(at 137.16 264.16 0)
			(effects
				(font
					(size 1.27 1.27)
					(thickness 0.15)
				)
				(justify left bottom)
				(hide yes)
			)
		)
		(property "Datasheet" "https://www.murata.com/products/productdetail?partno=GRM155R61H104KE14%23"
			(at 139.7 264.16 0)
			(effects
				(font
					(size 1.27 1.27)
					(thickness 0.15)
				)
				(justify left bottom)
				(hide yes)
			)
		)
		(property "Description" ""
			(at 124.46 243.84 0)
			(effects
				(font
					(size 1.27 1.27)
				)
			)
		)
		(property "Manufacturer" "Murata"
			(at 144.78 264.16 0)
			(effects
				(font
					(size 1.27 1.27)
					(thickness 0.15)
				)
				(justify left bottom)
				(hide yes)
			)
		)
		(property "MPN" "GRM155R61H104KE14D"
			(at 142.24 264.16 0)
			(effects
				(font
					(size 1.27 1.27)
					(thickness 0.15)
				)
				(justify left bottom)
				(hide yes)
			)
		)
		(property "Val" "100n"
			(at 125.095 248.285 90)
			(effects
				(font
					(size 1.27 1.27)
					(thickness 0.15)
				)
				(justify right)
			)
		)
		(property "License" "Apache-2.0"
			(at 147.32 264.16 0)
			(effects
				(font
					(size 1.27 1.27)
					(thickness 0.15)
				)
				(justify left bottom)
				(hide yes)
			)
		)
		(property "Author" "Antmicro"
			(at 149.86 264.16 0)
			(effects
				(font
					(size 1.27 1.27)
					(thickness 0.15)
				)
				(justify left bottom)
				(hide yes)
			)
		)
		(property "Voltage" "50V"
			(at 152.4 264.16 0)
			(effects
				(font
					(size 1.27 1.27)
				)
				(justify left bottom)
				(hide yes)
			)
		)
		(property "Dielectric" "X5R"
			(at 154.94 264.16 0)
			(effects
				(font
					(size 1.27 1.27)
				)
				(justify left bottom)
				(hide yes)
			)
		)
		(pin "1"
		)
		(pin "2"
		)
		(instances
			(project "data-center-rdimm-ddr5-tester"
				(path ""
					(reference "C335")
					(unit 1)
				)
			)
		)
	)
	(symbol
		(lib_id "antmicropower:+1V1")
		(at 46.99 226.06 0)
		(unit 1)
		(exclude_from_sim no)
		(in_bom yes)
		(on_board yes)
		(dnp no)
		(fields_autoplaced yes)
		(property "Reference" "#PWR0552"
			(at 46.99 229.87 0)
			(effects
				(font
					(size 1.27 1.27)
				)
				(hide yes)
			)
		)
		(property "Value" "VDDQ"
			(at 46.99 222.504 0)
			(effects
				(font
					(size 1.27 1.27)
				)
			)
		)
		(property "Footprint" ""
			(at 46.99 226.06 0)
			(effects
				(font
					(size 1.27 1.27)
				)
				(hide yes)
			)
		)
		(property "Datasheet" ""
			(at 46.99 226.06 0)
			(effects
				(font
					(size 1.27 1.27)
				)
				(hide yes)
			)
		)
		(property "Description" ""
			(at 46.99 226.06 0)
			(effects
				(font
					(size 1.27 1.27)
				)
				(hide yes)
			)
		)
		(pin "1"
		)
		(instances
			(project "data-center-rdimm-ddr5-tester"
				(path ""
					(reference "#PWR0552")
					(unit 1)
				)
			)
		)
	)
	(symbol
		(lib_id "antmicroResistors0402:R_1k_0402")
		(at 46.99 242.57 90)
		(unit 1)
		(exclude_from_sim no)
		(in_bom yes)
		(on_board yes)
		(dnp no)
		(fields_autoplaced yes)
		(property "Reference" "R254"
			(at 48.641 239.1994 90)
			(effects
				(font
					(size 1.27 1.27)
					(thickness 0.15)
				)
				(justify right)
			)
		)
		(property "Value" "R_1k_0402"
			(at 59.69 222.25 0)
			(effects
				(font
					(size 1.27 1.27)
					(thickness 0.15)
				)
				(justify left bottom)
				(hide yes)
			)
		)
		(property "Footprint" "antmicro-footprints:R_0402_1005Metric"
			(at 62.23 222.25 0)
			(effects
				(font
					(size 1.27 1.27)
					(thickness 0.15)
				)
				(justify left bottom)
				(hide yes)
			)
		)
		(property "Datasheet" "https://www.bourns.com/docs/product-datasheets/cr.pdf"
			(at 64.77 222.25 0)
			(effects
				(font
					(size 1.27 1.27)
					(thickness 0.15)
				)
				(justify left bottom)
				(hide yes)
			)
		)
		(property "Description" ""
			(at 46.99 242.57 0)
			(effects
				(font
					(size 1.27 1.27)
				)
			)
		)
		(property "MPN" "CR0402-FX-1001GLF"
			(at 67.31 222.25 0)
			(effects
				(font
					(size 1.27 1.27)
					(thickness 0.15)
				)
				(justify left bottom)
				(hide yes)
			)
		)
		(property "Manufacturer" "Bourns"
			(at 69.85 222.25 0)
			(effects
				(font
					(size 1.27 1.27)
					(thickness 0.15)
				)
				(justify left bottom)
				(hide yes)
			)
		)
		(property "License" "Apache-2.0"
			(at 72.39 222.25 0)
			(effects
				(font
					(size 1.27 1.27)
					(thickness 0.15)
				)
				(justify left bottom)
				(hide yes)
			)
		)
		(property "Author" "Antmicro"
			(at 74.93 222.25 0)
			(effects
				(font
					(size 1.27 1.27)
					(thickness 0.15)
				)
				(justify left bottom)
				(hide yes)
			)
		)
		(property "Val" "1k"
			(at 48.641 241.7231 90)
			(effects
				(font
					(size 1.27 1.27)
					(thickness 0.15)
				)
				(justify right)
			)
		)
		(property "Tolerance" "1%"
			(at 57.15 222.25 0)
			(effects
				(font
					(size 1.27 1.27)
				)
				(justify left bottom)
				(hide yes)
			)
		)
		(pin "1"
		)
		(pin "2"
		)
		(instances
			(project "data-center-rdimm-ddr5-tester"
				(path ""
					(reference "R254")
					(unit 1)
				)
			)
		)
	)
	(symbol
		(lib_id "antmicropower:GND")
		(at 83.82 250.19 0)
		(mirror y)
		(unit 1)
		(exclude_from_sim no)
		(in_bom yes)
		(on_board yes)
		(dnp no)
		(property "Reference" "#PWR0559"
			(at 83.82 256.54 0)
			(effects
				(font
					(size 1.27 1.27)
				)
				(hide yes)
			)
		)
		(property "Value" "GND"
			(at 83.82 253.746 0)
			(effects
				(font
					(size 1.27 1.27)
					(thickness 0.15)
				)
			)
		)
		(property "Footprint" ""
			(at 74.93 257.81 0)
			(effects
				(font
					(size 1.27 1.27)
					(thickness 0.15)
				)
				(justify left bottom)
				(hide yes)
			)
		)
		(property "Datasheet" ""
			(at 74.93 262.89 0)
			(effects
				(font
					(size 1.27 1.27)
					(thickness 0.15)
				)
				(justify left bottom)
				(hide yes)
			)
		)
		(property "Description" ""
			(at 74.93 265.43 0)
			(effects
				(font
					(size 1.27 1.27)
				)
				(justify left bottom)
				(hide yes)
			)
		)
		(property "Author" "Antmicro"
			(at 74.93 257.81 0)
			(effects
				(font
					(size 1.27 1.27)
					(thickness 0.15)
				)
				(justify left bottom)
				(hide yes)
			)
		)
		(property "License" "Apache-2.0"
			(at 74.93 260.35 0)
			(effects
				(font
					(size 1.27 1.27)
					(thickness 0.15)
				)
				(justify left bottom)
				(hide yes)
			)
		)
		(pin "1"
		)
		(instances
			(project "data-center-rdimm-ddr5-tester"
				(path ""
					(reference "#PWR0559")
					(unit 1)
				)
			)
		)
	)
	(symbol
		(lib_id "antmicroResistors0402:R_0R_0402")
		(at 154.94 241.3 90)
		(unit 1)
		(exclude_from_sim no)
		(in_bom yes)
		(on_board yes)
		(dnp no)
		(property "Reference" "R260"
			(at 156.21 237.49 90)
			(effects
				(font
					(size 1.27 1.27)
					(thickness 0.15)
				)
				(justify right)
			)
		)
		(property "Value" "R_0R_0402"
			(at 167.64 220.98 0)
			(effects
				(font
					(size 1.27 1.27)
					(thickness 0.15)
				)
				(justify left bottom)
				(hide yes)
			)
		)
		(property "Footprint" "antmicro-footprints:R_0402_1005Metric"
			(at 170.18 220.98 0)
			(effects
				(font
					(size 1.27 1.27)
					(thickness 0.15)
				)
				(justify left bottom)
				(hide yes)
			)
		)
		(property "Datasheet" "https://industrial.panasonic.com/cdbs/www-data/pdf/RDA0000/AOA0000C301.pdf"
			(at 172.72 220.98 0)
			(effects
				(font
					(size 1.27 1.27)
					(thickness 0.15)
				)
				(justify left bottom)
				(hide yes)
			)
		)
		(property "Description" ""
			(at 154.94 241.3 0)
			(effects
				(font
					(size 1.27 1.27)
				)
			)
		)
		(property "MPN" "ERJ2GE0R00X"
			(at 175.26 220.98 0)
			(effects
				(font
					(size 1.27 1.27)
					(thickness 0.15)
				)
				(justify left bottom)
				(hide yes)
			)
		)
		(property "Manufacturer" "Panasonic"
			(at 177.8 220.98 0)
			(effects
				(font
					(size 1.27 1.27)
					(thickness 0.15)
				)
				(justify left bottom)
				(hide yes)
			)
		)
		(property "License" "Apache-2.0"
			(at 180.34 220.98 0)
			(effects
				(font
					(size 1.27 1.27)
					(thickness 0.15)
				)
				(justify left bottom)
				(hide yes)
			)
		)
		(property "Author" "Antmicro"
			(at 182.88 220.98 0)
			(effects
				(font
					(size 1.27 1.27)
					(thickness 0.15)
				)
				(justify left bottom)
				(hide yes)
			)
		)
		(property "Val" "0R"
			(at 156.21 240.03 90)
			(effects
				(font
					(size 1.27 1.27)
					(thickness 0.15)
				)
				(justify right)
			)
		)
		(property "Tolerance" "~"
			(at 165.1 220.98 0)
			(effects
				(font
					(size 1.27 1.27)
				)
				(justify left bottom)
				(hide yes)
			)
		)
		(property "Current" "1A"
			(at 185.42 220.98 0)
			(effects
				(font
					(size 1.27 1.27)
					(thickness 0.15)
				)
				(justify left bottom)
				(hide yes)
			)
		)
		(pin "1"
		)
		(pin "2"
		)
		(instances
			(project "data-center-rdimm-ddr5-tester"
				(path ""
					(reference "R260")
					(unit 1)
				)
			)
		)
	)
	(symbol
		(lib_id "antmicropower:GND")
		(at 335.28 238.76 0)
		(unit 1)
		(exclude_from_sim no)
		(in_bom yes)
		(on_board yes)
		(dnp no)
		(property "Reference" "#PWR0263"
			(at 344.17 241.3 0)
			(effects
				(font
					(size 1.27 1.27)
					(thickness 0.15)
				)
				(justify left bottom)
				(hide yes)
			)
		)
		(property "Value" "GND"
			(at 335.28 242.57 0)
			(effects
				(font
					(size 1.27 1.27)
					(thickness 0.15)
				)
			)
		)
		(property "Footprint" ""
			(at 344.17 246.38 0)
			(effects
				(font
					(size 1.27 1.27)
					(thickness 0.15)
				)
				(justify left bottom)
				(hide yes)
			)
		)
		(property "Datasheet" ""
			(at 344.17 251.46 0)
			(effects
				(font
					(size 1.27 1.27)
					(thickness 0.15)
				)
				(justify left bottom)
				(hide yes)
			)
		)
		(property "Description" ""
			(at 335.28 238.76 0)
			(effects
				(font
					(size 1.27 1.27)
				)
				(hide yes)
			)
		)
		(property "Author" "Antmicro"
			(at 344.17 246.38 0)
			(effects
				(font
					(size 1.27 1.27)
					(thickness 0.15)
				)
				(justify left bottom)
				(hide yes)
			)
		)
		(property "License" "Apache-2.0"
			(at 344.17 248.92 0)
			(effects
				(font
					(size 1.27 1.27)
					(thickness 0.15)
				)
				(justify left bottom)
				(hide yes)
			)
		)
		(pin "1"
		)
		(instances
			(project "data-center-rdimm-ddr5-tester"
				(path ""
					(reference "#PWR0263")
					(unit 1)
				)
			)
		)
	)
	(symbol
		(lib_id "antmicropower:+1V1")
		(at 142.24 48.26 0)
		(unit 1)
		(exclude_from_sim no)
		(in_bom yes)
		(on_board yes)
		(dnp no)
		(fields_autoplaced yes)
		(property "Reference" "#PWR0323"
			(at 142.24 52.07 0)
			(effects
				(font
					(size 1.27 1.27)
				)
				(hide yes)
			)
		)
		(property "Value" "VDDQ"
			(at 142.24 44.704 0)
			(effects
				(font
					(size 1.27 1.27)
				)
			)
		)
		(property "Footprint" ""
			(at 142.24 48.26 0)
			(effects
				(font
					(size 1.27 1.27)
				)
				(hide yes)
			)
		)
		(property "Datasheet" ""
			(at 142.24 48.26 0)
			(effects
				(font
					(size 1.27 1.27)
				)
				(hide yes)
			)
		)
		(property "Description" ""
			(at 142.24 48.26 0)
			(effects
				(font
					(size 1.27 1.27)
				)
				(hide yes)
			)
		)
		(pin "1"
		)
		(instances
			(project "data-center-rdimm-ddr5-tester"
				(path ""
					(reference "#PWR0323")
					(unit 1)
				)
			)
		)
	)
	(symbol
		(lib_id "antmicropower:GND")
		(at 260.35 242.57 0)
		(mirror y)
		(unit 1)
		(exclude_from_sim no)
		(in_bom yes)
		(on_board yes)
		(dnp no)
		(fields_autoplaced yes)
		(property "Reference" "#PWR0282"
			(at 260.35 248.92 0)
			(effects
				(font
					(size 1.27 1.27)
				)
				(hide yes)
			)
		)
		(property "Value" "GND"
			(at 262.255 247.015 0)
			(effects
				(font
					(size 1.27 1.27)
					(thickness 0.15)
				)
				(justify left bottom)
			)
		)
		(property "Footprint" ""
			(at 251.46 250.19 0)
			(effects
				(font
					(size 1.27 1.27)
					(thickness 0.15)
				)
				(justify left bottom)
				(hide yes)
			)
		)
		(property "Datasheet" ""
			(at 251.46 255.27 0)
			(effects
				(font
					(size 1.27 1.27)
					(thickness 0.15)
				)
				(justify left bottom)
				(hide yes)
			)
		)
		(property "Description" ""
			(at 260.35 242.57 0)
			(effects
				(font
					(size 1.27 1.27)
				)
				(hide yes)
			)
		)
		(property "Author" "Antmicro"
			(at 251.46 247.65 0)
			(effects
				(font
					(size 1.27 1.27)
					(thickness 0.15)
				)
				(justify left bottom)
				(hide yes)
			)
		)
		(property "License" "Apache-2.0"
			(at 251.46 250.19 0)
			(effects
				(font
					(size 1.27 1.27)
					(thickness 0.15)
				)
				(justify left bottom)
				(hide yes)
			)
		)
		(pin "1"
		)
		(instances
			(project "data-center-rdimm-ddr5-tester"
				(path ""
					(reference "#PWR0282")
					(unit 1)
				)
			)
		)
	)
	(symbol
		(lib_id "antmicroResistors0402:R_240R_0402")
		(at 231.14 240.03 0)
		(unit 1)
		(exclude_from_sim no)
		(in_bom yes)
		(on_board yes)
		(dnp no)
		(fields_autoplaced yes)
		(property "Reference" "R133"
			(at 233.68 233.68 0)
			(effects
				(font
					(size 1.27 1.27)
					(thickness 0.15)
				)
			)
		)
		(property "Value" "R_240R_0402"
			(at 251.46 252.73 0)
			(effects
				(font
					(size 1.27 1.27)
					(thickness 0.15)
				)
				(justify left bottom)
				(hide yes)
			)
		)
		(property "Footprint" "antmicro-footprints:R_0402_1005Metric_EIA"
			(at 251.46 255.27 0)
			(effects
				(font
					(size 1.27 1.27)
					(thickness 0.15)
				)
				(justify left bottom)
				(hide yes)
			)
		)
		(property "Datasheet" "https://www.bourns.com/docs/product-datasheets/cr.pdf"
			(at 251.46 257.81 0)
			(effects
				(font
					(size 1.27 1.27)
					(thickness 0.15)
				)
				(justify left bottom)
				(hide yes)
			)
		)
		(property "Description" ""
			(at 231.14 240.03 0)
			(effects
				(font
					(size 1.27 1.27)
				)
				(hide yes)
			)
		)
		(property "MPN" "CR0402-FX-2400GLF"
			(at 251.46 260.35 0)
			(effects
				(font
					(size 1.27 1.27)
					(thickness 0.15)
				)
				(justify left bottom)
				(hide yes)
			)
		)
		(property "Manufacturer" "Bourns"
			(at 251.46 262.89 0)
			(effects
				(font
					(size 1.27 1.27)
					(thickness 0.15)
				)
				(justify left bottom)
				(hide yes)
			)
		)
		(property "License" "Apache-2.0"
			(at 251.46 265.43 0)
			(effects
				(font
					(size 1.27 1.27)
					(thickness 0.15)
				)
				(justify left bottom)
				(hide yes)
			)
		)
		(property "Author" "Antmicro"
			(at 251.46 267.97 0)
			(effects
				(font
					(size 1.27 1.27)
					(thickness 0.15)
				)
				(justify left bottom)
				(hide yes)
			)
		)
		(property "Val" "240R"
			(at 233.68 236.22 0)
			(effects
				(font
					(size 1.27 1.27)
					(thickness 0.15)
				)
			)
		)
		(property "Tolerance" "1%"
			(at 251.46 250.19 0)
			(effects
				(font
					(size 1.27 1.27)
				)
				(justify left bottom)
				(hide yes)
			)
		)
		(pin "1"
		)
		(pin "2"
		)
		(instances
			(project "data-center-rdimm-ddr5-tester"
				(path ""
					(reference "R133")
					(unit 1)
				)
			)
		)
	)
	(symbol
		(lib_id "antmicropower:GND")
		(at 345.44 242.57 0)
		(unit 1)
		(exclude_from_sim no)
		(in_bom yes)
		(on_board yes)
		(dnp no)
		(property "Reference" "#PWR0262"
			(at 354.33 245.11 0)
			(effects
				(font
					(size 1.27 1.27)
					(thickness 0.15)
				)
				(justify left bottom)
				(hide yes)
			)
		)
		(property "Value" "GND"
			(at 345.44 246.38 0)
			(effects
				(font
					(size 1.27 1.27)
					(thickness 0.15)
				)
			)
		)
		(property "Footprint" ""
			(at 354.33 250.19 0)
			(effects
				(font
					(size 1.27 1.27)
					(thickness 0.15)
				)
				(justify left bottom)
				(hide yes)
			)
		)
		(property "Datasheet" ""
			(at 354.33 255.27 0)
			(effects
				(font
					(size 1.27 1.27)
					(thickness 0.15)
				)
				(justify left bottom)
				(hide yes)
			)
		)
		(property "Description" ""
			(at 345.44 242.57 0)
			(effects
				(font
					(size 1.27 1.27)
				)
				(hide yes)
			)
		)
		(property "Author" "Antmicro"
			(at 354.33 250.19 0)
			(effects
				(font
					(size 1.27 1.27)
					(thickness 0.15)
				)
				(justify left bottom)
				(hide yes)
			)
		)
		(property "License" "Apache-2.0"
			(at 354.33 252.73 0)
			(effects
				(font
					(size 1.27 1.27)
					(thickness 0.15)
				)
				(justify left bottom)
				(hide yes)
			)
		)
		(pin "1"
		)
		(instances
			(project "data-center-rdimm-ddr5-tester"
				(path ""
					(reference "#PWR0262")
					(unit 1)
				)
			)
		)
	)
	(symbol
		(lib_id "antmicropower:GND")
		(at 154.94 250.19 0)
		(mirror y)
		(unit 1)
		(exclude_from_sim no)
		(in_bom yes)
		(on_board yes)
		(dnp no)
		(fields_autoplaced yes)
		(property "Reference" "#PWR0280"
			(at 154.94 256.54 0)
			(effects
				(font
					(size 1.27 1.27)
				)
				(hide yes)
			)
		)
		(property "Value" "GND"
			(at 156.845 254.635 0)
			(effects
				(font
					(size 1.27 1.27)
					(thickness 0.15)
				)
				(justify left bottom)
			)
		)
		(property "Footprint" ""
			(at 146.05 257.81 0)
			(effects
				(font
					(size 1.27 1.27)
					(thickness 0.15)
				)
				(justify left bottom)
				(hide yes)
			)
		)
		(property "Datasheet" ""
			(at 146.05 262.89 0)
			(effects
				(font
					(size 1.27 1.27)
					(thickness 0.15)
				)
				(justify left bottom)
				(hide yes)
			)
		)
		(property "Description" ""
			(at 154.94 250.19 0)
			(effects
				(font
					(size 1.27 1.27)
				)
				(hide yes)
			)
		)
		(property "Author" "Antmicro"
			(at 146.05 255.27 0)
			(effects
				(font
					(size 1.27 1.27)
					(thickness 0.15)
				)
				(justify left bottom)
				(hide yes)
			)
		)
		(property "License" "Apache-2.0"
			(at 146.05 257.81 0)
			(effects
				(font
					(size 1.27 1.27)
					(thickness 0.15)
				)
				(justify left bottom)
				(hide yes)
			)
		)
		(pin "1"
		)
		(instances
			(project "data-center-rdimm-ddr5-tester"
				(path ""
					(reference "#PWR0280")
					(unit 1)
				)
			)
		)
	)
	(symbol
		(lib_id "antmicroOscillators:Oscillator_100MHz_SG3225VAN")
		(at 346.71 236.22 0)
		(unit 1)
		(exclude_from_sim no)
		(in_bom yes)
		(on_board yes)
		(dnp no)
		(fields_autoplaced yes)
		(property "Reference" "Y3"
			(at 356.235 226.06 0)
			(effects
				(font
					(size 1.27 1.27)
					(thickness 0.15)
				)
			)
		)
		(property "Value" "Oscillator_100MHz_SG3225VAN"
			(at 367.03 256.54 0)
			(effects
				(font
					(size 1.27 1.27)
					(thickness 0.15)
				)
				(justify left bottom)
				(hide yes)
			)
		)
		(property "Footprint" "antmicro-footprints:Oscillator_SMD_Epson_SG3225EEN_3.2x2.5x1.2mm"
			(at 367.03 259.08 0)
			(effects
				(font
					(size 1.27 1.27)
					(thickness 0.15)
				)
				(justify left bottom)
				(hide yes)
			)
		)
		(property "Datasheet" "https://support.epson.biz/td/api/doc_check.php?dl=brief_SG5032VAN&lang=en"
			(at 367.03 261.62 0)
			(effects
				(font
					(size 1.27 1.27)
					(thickness 0.15)
				)
				(justify left bottom)
				(hide yes)
			)
		)
		(property "Description" ""
			(at 346.71 236.22 0)
			(effects
				(font
					(size 1.27 1.27)
				)
				(hide yes)
			)
		)
		(property "Manufacturer" "Epson"
			(at 367.03 248.92 0)
			(effects
				(font
					(size 1.27 1.27)
					(thickness 0.15)
				)
				(justify left bottom)
				(hide yes)
			)
		)
		(property "MPN" "SG3225VAN_100.000000M-KEGA3"
			(at 356.235 228.6 0)
			(effects
				(font
					(size 1.27 1.27)
					(thickness 0.15)
				)
			)
		)
		(property "Val" "100MHz"
			(at 356.235 231.14 0)
			(effects
				(font
					(size 1.27 1.27)
					(thickness 0.15)
				)
			)
		)
		(property "Author" "Antmicro"
			(at 367.03 264.16 0)
			(effects
				(font
					(size 1.27 1.27)
					(thickness 0.15)
				)
				(justify left bottom)
				(hide yes)
			)
		)
		(property "License" "Apache-2.0"
			(at 367.03 266.7 0)
			(effects
				(font
					(size 1.27 1.27)
					(thickness 0.15)
				)
				(justify left bottom)
				(hide yes)
			)
		)
		(pin "2"
		)
		(pin "5"
		)
		(pin "1"
		)
		(pin "4"
		)
		(pin "3"
		)
		(pin "6"
		)
		(instances
			(project "data-center-rdimm-ddr5-tester"
				(path ""
					(reference "Y3")
					(unit 1)
				)
			)
		)
	)
	(symbol
		(lib_id "antmicropower:+1V1")
		(at 241.3 48.26 0)
		(unit 1)
		(exclude_from_sim no)
		(in_bom yes)
		(on_board yes)
		(dnp no)
		(fields_autoplaced yes)
		(property "Reference" "#PWR0189"
			(at 241.3 52.07 0)
			(effects
				(font
					(size 1.27 1.27)
				)
				(hide yes)
			)
		)
		(property "Value" "VDDQ"
			(at 241.3 44.704 0)
			(effects
				(font
					(size 1.27 1.27)
				)
			)
		)
		(property "Footprint" ""
			(at 241.3 48.26 0)
			(effects
				(font
					(size 1.27 1.27)
				)
				(hide yes)
			)
		)
		(property "Datasheet" ""
			(at 241.3 48.26 0)
			(effects
				(font
					(size 1.27 1.27)
				)
				(hide yes)
			)
		)
		(property "Description" ""
			(at 241.3 48.26 0)
			(effects
				(font
					(size 1.27 1.27)
				)
				(hide yes)
			)
		)
		(pin "1"
		)
		(instances
			(project "data-center-rdimm-ddr5-tester"
				(path ""
					(reference "#PWR0189")
					(unit 1)
				)
			)
		)
	)
	(symbol
		(lib_id "antmicropower:GND")
		(at 144.78 250.19 0)
		(mirror y)
		(unit 1)
		(exclude_from_sim no)
		(in_bom yes)
		(on_board yes)
		(dnp no)
		(property "Reference" "#PWR0561"
			(at 144.78 256.54 0)
			(effects
				(font
					(size 1.27 1.27)
				)
				(hide yes)
			)
		)
		(property "Value" "GND"
			(at 144.78 253.746 0)
			(effects
				(font
					(size 1.27 1.27)
					(thickness 0.15)
				)
			)
		)
		(property "Footprint" ""
			(at 135.89 257.81 0)
			(effects
				(font
					(size 1.27 1.27)
					(thickness 0.15)
				)
				(justify left bottom)
				(hide yes)
			)
		)
		(property "Datasheet" ""
			(at 135.89 262.89 0)
			(effects
				(font
					(size 1.27 1.27)
					(thickness 0.15)
				)
				(justify left bottom)
				(hide yes)
			)
		)
		(property "Description" ""
			(at 135.89 265.43 0)
			(effects
				(font
					(size 1.27 1.27)
				)
				(justify left bottom)
				(hide yes)
			)
		)
		(property "Author" "Antmicro"
			(at 135.89 257.81 0)
			(effects
				(font
					(size 1.27 1.27)
					(thickness 0.15)
				)
				(justify left bottom)
				(hide yes)
			)
		)
		(property "License" "Apache-2.0"
			(at 135.89 260.35 0)
			(effects
				(font
					(size 1.27 1.27)
					(thickness 0.15)
				)
				(justify left bottom)
				(hide yes)
			)
		)
		(pin "1"
		)
		(instances
			(project "data-center-rdimm-ddr5-tester"
				(path ""
					(reference "#PWR0561")
					(unit 1)
				)
			)
		)
	)
	(symbol
		(lib_id "antmicropower:GND")
		(at 134.62 250.19 0)
		(mirror y)
		(unit 1)
		(exclude_from_sim no)
		(in_bom yes)
		(on_board yes)
		(dnp no)
		(fields_autoplaced yes)
		(property "Reference" "#PWR0279"
			(at 134.62 256.54 0)
			(effects
				(font
					(size 1.27 1.27)
				)
				(hide yes)
			)
		)
		(property "Value" "GND"
			(at 136.525 254.635 0)
			(effects
				(font
					(size 1.27 1.27)
					(thickness 0.15)
				)
				(justify left bottom)
			)
		)
		(property "Footprint" ""
			(at 125.73 257.81 0)
			(effects
				(font
					(size 1.27 1.27)
					(thickness 0.15)
				)
				(justify left bottom)
				(hide yes)
			)
		)
		(property "Datasheet" ""
			(at 125.73 262.89 0)
			(effects
				(font
					(size 1.27 1.27)
					(thickness 0.15)
				)
				(justify left bottom)
				(hide yes)
			)
		)
		(property "Description" ""
			(at 134.62 250.19 0)
			(effects
				(font
					(size 1.27 1.27)
				)
				(hide yes)
			)
		)
		(property "Author" "Antmicro"
			(at 125.73 255.27 0)
			(effects
				(font
					(size 1.27 1.27)
					(thickness 0.15)
				)
				(justify left bottom)
				(hide yes)
			)
		)
		(property "License" "Apache-2.0"
			(at 125.73 257.81 0)
			(effects
				(font
					(size 1.27 1.27)
					(thickness 0.15)
				)
				(justify left bottom)
				(hide yes)
			)
		)
		(pin "1"
		)
		(instances
			(project "data-center-rdimm-ddr5-tester"
				(path ""
					(reference "#PWR0279")
					(unit 1)
				)
			)
		)
	)
	(symbol
		(lib_id "antmicroResistors0402:R_0R_0402")
		(at 76.2 234.95 0)
		(unit 1)
		(exclude_from_sim no)
		(in_bom no)
		(on_board yes)
		(dnp yes)
		(property "Reference" "R256"
			(at 78.74 230.376 0)
			(effects
				(font
					(size 1.27 1.27)
					(thickness 0.15)
				)
			)
		)
		(property "Value" "R_0R_0402"
			(at 96.52 247.65 0)
			(effects
				(font
					(size 1.27 1.27)
					(thickness 0.15)
				)
				(justify left bottom)
				(hide yes)
			)
		)
		(property "Footprint" "antmicro-footprints:R_0402_1005Metric"
			(at 96.52 250.19 0)
			(effects
				(font
					(size 1.27 1.27)
					(thickness 0.15)
				)
				(justify left bottom)
				(hide yes)
			)
		)
		(property "Datasheet" "https://industrial.panasonic.com/cdbs/www-data/pdf/RDA0000/AOA0000C301.pdf"
			(at 96.52 252.73 0)
			(effects
				(font
					(size 1.27 1.27)
					(thickness 0.15)
				)
				(justify left bottom)
				(hide yes)
			)
		)
		(property "Description" ""
			(at 76.2 234.95 0)
			(effects
				(font
					(size 1.27 1.27)
				)
			)
		)
		(property "MPN" "ERJ2GE0R00X"
			(at 96.52 255.27 0)
			(effects
				(font
					(size 1.27 1.27)
					(thickness 0.15)
				)
				(justify left bottom)
				(hide yes)
			)
		)
		(property "Manufacturer" "Panasonic"
			(at 96.52 257.81 0)
			(effects
				(font
					(size 1.27 1.27)
					(thickness 0.15)
				)
				(justify left bottom)
				(hide yes)
			)
		)
		(property "License" "Apache-2.0"
			(at 96.52 260.35 0)
			(effects
				(font
					(size 1.27 1.27)
					(thickness 0.15)
				)
				(justify left bottom)
				(hide yes)
			)
		)
		(property "Author" "Antmicro"
			(at 96.52 262.89 0)
			(effects
				(font
					(size 1.27 1.27)
					(thickness 0.15)
				)
				(justify left bottom)
				(hide yes)
			)
		)
		(property "Val" "0R"
			(at 78.74 232.8997 0)
			(effects
				(font
					(size 1.27 1.27)
					(thickness 0.15)
				)
			)
		)
		(property "Tolerance" "~"
			(at 96.52 245.11 0)
			(effects
				(font
					(size 1.27 1.27)
				)
				(justify left bottom)
				(hide yes)
			)
		)
		(property "Current" "1A"
			(at 96.52 265.43 0)
			(effects
				(font
					(size 1.27 1.27)
					(thickness 0.15)
				)
				(justify left bottom)
				(hide yes)
			)
		)
		(pin "1"
		)
		(pin "2"
		)
		(instances
			(project "data-center-rdimm-ddr5-tester"
				(path ""
					(reference "R256")
					(unit 1)
				)
			)
		)
	)
	(symbol
		(lib_id "antmicropower:+1V8")
		(at 344.17 49.53 0)
		(unit 1)
		(exclude_from_sim no)
		(in_bom yes)
		(on_board yes)
		(dnp no)
		(fields_autoplaced yes)
		(property "Reference" "#PWR0378"
			(at 359.41 52.07 0)
			(effects
				(font
					(size 1.27 1.27)
					(thickness 0.15)
				)
				(justify left bottom)
				(hide yes)
			)
		)
		(property "Value" "+1V8"
			(at 344.17 45.72 0)
			(effects
				(font
					(size 1.27 1.27)
					(thickness 0.15)
				)
			)
		)
		(property "Footprint" ""
			(at 359.41 57.15 0)
			(effects
				(font
					(size 1.27 1.27)
					(thickness 0.15)
				)
				(justify left bottom)
				(hide yes)
			)
		)
		(property "Datasheet" ""
			(at 359.41 59.69 0)
			(effects
				(font
					(size 1.27 1.27)
					(thickness 0.15)
				)
				(justify left bottom)
				(hide yes)
			)
		)
		(property "Description" ""
			(at 344.17 49.53 0)
			(effects
				(font
					(size 1.27 1.27)
				)
				(hide yes)
			)
		)
		(property "Author" "Antmicro"
			(at 359.41 54.61 0)
			(effects
				(font
					(size 1.27 1.27)
					(thickness 0.15)
				)
				(justify left bottom)
				(hide yes)
			)
		)
		(property "License" "Apache-2.0"
			(at 359.41 57.15 0)
			(effects
				(font
					(size 1.27 1.27)
					(thickness 0.15)
				)
				(justify left bottom)
				(hide yes)
			)
		)
		(pin "1"
		)
		(instances
			(project "data-center-rdimm-ddr5-tester"
				(path ""
					(reference "#PWR0378")
					(unit 1)
				)
			)
		)
	)
	(symbol
		(lib_id "antmicroCapacitors0402:C_100n_0402")
		(at 335.28 238.76 90)
		(unit 1)
		(exclude_from_sim no)
		(in_bom yes)
		(on_board yes)
		(dnp no)
		(property "Reference" "C164"
			(at 332.74 234.9436 90)
			(effects
				(font
					(size 1.27 1.27)
					(thickness 0.15)
				)
				(justify left)
			)
		)
		(property "Value" "C_100n_0402"
			(at 345.44 218.44 0)
			(effects
				(font
					(size 1.27 1.27)
					(thickness 0.15)
				)
				(justify left bottom)
				(hide yes)
			)
		)
		(property "Footprint" "antmicro-footprints:C_0402_1005Metric"
			(at 347.98 218.44 0)
			(effects
				(font
					(size 1.27 1.27)
					(thickness 0.15)
				)
				(justify left bottom)
				(hide yes)
			)
		)
		(property "Datasheet" "https://www.murata.com/products/productdetail?partno=GRM155R61H104KE14%23"
			(at 350.52 218.44 0)
			(effects
				(font
					(size 1.27 1.27)
					(thickness 0.15)
				)
				(justify left bottom)
				(hide yes)
			)
		)
		(property "Description" ""
			(at 335.28 238.76 0)
			(effects
				(font
					(size 1.27 1.27)
				)
				(hide yes)
			)
		)
		(property "MPN" "GRM155R61H104KE14D"
			(at 353.06 218.44 0)
			(effects
				(font
					(size 1.27 1.27)
					(thickness 0.15)
				)
				(justify left bottom)
				(hide yes)
			)
		)
		(property "Manufacturer" "Murata"
			(at 355.6 218.44 0)
			(effects
				(font
					(size 1.27 1.27)
					(thickness 0.15)
				)
				(justify left bottom)
				(hide yes)
			)
		)
		(property "License" "Apache-2.0"
			(at 358.14 218.44 0)
			(effects
				(font
					(size 1.27 1.27)
					(thickness 0.15)
				)
				(justify left bottom)
				(hide yes)
			)
		)
		(property "Author" "Antmicro"
			(at 360.68 218.44 0)
			(effects
				(font
					(size 1.27 1.27)
					(thickness 0.15)
				)
				(justify left bottom)
				(hide yes)
			)
		)
		(property "Val" "100n"
			(at 332.74 237.4836 90)
			(effects
				(font
					(size 1.27 1.27)
					(thickness 0.15)
				)
				(justify left)
			)
		)
		(property "Voltage" "50V"
			(at 363.22 218.44 0)
			(effects
				(font
					(size 1.27 1.27)
				)
				(justify left bottom)
				(hide yes)
			)
		)
		(property "Dielectric" "X5R"
			(at 365.76 218.44 0)
			(effects
				(font
					(size 1.27 1.27)
				)
				(justify left bottom)
				(hide yes)
			)
		)
		(pin "1"
		)
		(pin "2"
		)
		(instances
			(project "data-center-rdimm-ddr5-tester"
				(path ""
					(reference "C164")
					(unit 1)
				)
			)
		)
	)
	(symbol
		(lib_id "antmicroResistors0402:R_240R_0402")
		(at 251.46 257.81 0)
		(unit 1)
		(exclude_from_sim no)
		(in_bom yes)
		(on_board yes)
		(dnp no)
		(fields_autoplaced yes)
		(property "Reference" "R182"
			(at 254 251.46 0)
			(effects
				(font
					(size 1.27 1.27)
					(thickness 0.15)
				)
			)
		)
		(property "Value" "R_240R_0402"
			(at 271.78 270.51 0)
			(effects
				(font
					(size 1.27 1.27)
					(thickness 0.15)
				)
				(justify left bottom)
				(hide yes)
			)
		)
		(property "Footprint" "antmicro-footprints:R_0402_1005Metric_EIA"
			(at 271.78 273.05 0)
			(effects
				(font
					(size 1.27 1.27)
					(thickness 0.15)
				)
				(justify left bottom)
				(hide yes)
			)
		)
		(property "Datasheet" "https://www.bourns.com/docs/product-datasheets/cr.pdf"
			(at 271.78 275.59 0)
			(effects
				(font
					(size 1.27 1.27)
					(thickness 0.15)
				)
				(justify left bottom)
				(hide yes)
			)
		)
		(property "Description" ""
			(at 251.46 257.81 0)
			(effects
				(font
					(size 1.27 1.27)
				)
				(hide yes)
			)
		)
		(property "MPN" "CR0402-FX-2400GLF"
			(at 271.78 278.13 0)
			(effects
				(font
					(size 1.27 1.27)
					(thickness 0.15)
				)
				(justify left bottom)
				(hide yes)
			)
		)
		(property "Manufacturer" "Bourns"
			(at 271.78 280.67 0)
			(effects
				(font
					(size 1.27 1.27)
					(thickness 0.15)
				)
				(justify left bottom)
				(hide yes)
			)
		)
		(property "License" "Apache-2.0"
			(at 271.78 283.21 0)
			(effects
				(font
					(size 1.27 1.27)
					(thickness 0.15)
				)
				(justify left bottom)
				(hide yes)
			)
		)
		(property "Author" "Antmicro"
			(at 271.78 285.75 0)
			(effects
				(font
					(size 1.27 1.27)
					(thickness 0.15)
				)
				(justify left bottom)
				(hide yes)
			)
		)
		(property "Val" "240R"
			(at 254 254 0)
			(effects
				(font
					(size 1.27 1.27)
					(thickness 0.15)
				)
			)
		)
		(property "Tolerance" "1%"
			(at 271.78 267.97 0)
			(effects
				(font
					(size 1.27 1.27)
				)
				(justify left bottom)
				(hide yes)
			)
		)
		(pin "1"
		)
		(pin "2"
		)
		(instances
			(project "data-center-rdimm-ddr5-tester"
				(path ""
					(reference "R182")
					(unit 1)
				)
			)
		)
	)
	(symbol
		(lib_id "antmicroResistors0402:R_240R_0402")
		(at 251.46 240.03 0)
		(unit 1)
		(exclude_from_sim no)
		(in_bom yes)
		(on_board yes)
		(dnp no)
		(fields_autoplaced yes)
		(property "Reference" "R134"
			(at 254 233.68 0)
			(effects
				(font
					(size 1.27 1.27)
					(thickness 0.15)
				)
			)
		)
		(property "Value" "R_240R_0402"
			(at 271.78 252.73 0)
			(effects
				(font
					(size 1.27 1.27)
					(thickness 0.15)
				)
				(justify left bottom)
				(hide yes)
			)
		)
		(property "Footprint" "antmicro-footprints:R_0402_1005Metric_EIA"
			(at 271.78 255.27 0)
			(effects
				(font
					(size 1.27 1.27)
					(thickness 0.15)
				)
				(justify left bottom)
				(hide yes)
			)
		)
		(property "Datasheet" "https://www.bourns.com/docs/product-datasheets/cr.pdf"
			(at 271.78 257.81 0)
			(effects
				(font
					(size 1.27 1.27)
					(thickness 0.15)
				)
				(justify left bottom)
				(hide yes)
			)
		)
		(property "Description" ""
			(at 251.46 240.03 0)
			(effects
				(font
					(size 1.27 1.27)
				)
				(hide yes)
			)
		)
		(property "MPN" "CR0402-FX-2400GLF"
			(at 271.78 260.35 0)
			(effects
				(font
					(size 1.27 1.27)
					(thickness 0.15)
				)
				(justify left bottom)
				(hide yes)
			)
		)
		(property "Manufacturer" "Bourns"
			(at 271.78 262.89 0)
			(effects
				(font
					(size 1.27 1.27)
					(thickness 0.15)
				)
				(justify left bottom)
				(hide yes)
			)
		)
		(property "License" "Apache-2.0"
			(at 271.78 265.43 0)
			(effects
				(font
					(size 1.27 1.27)
					(thickness 0.15)
				)
				(justify left bottom)
				(hide yes)
			)
		)
		(property "Author" "Antmicro"
			(at 271.78 267.97 0)
			(effects
				(font
					(size 1.27 1.27)
					(thickness 0.15)
				)
				(justify left bottom)
				(hide yes)
			)
		)
		(property "Val" "240R"
			(at 254 236.22 0)
			(effects
				(font
					(size 1.27 1.27)
					(thickness 0.15)
				)
			)
		)
		(property "Tolerance" "1%"
			(at 271.78 250.19 0)
			(effects
				(font
					(size 1.27 1.27)
				)
				(justify left bottom)
				(hide yes)
			)
		)
		(pin "1"
		)
		(pin "2"
		)
		(instances
			(project "data-center-rdimm-ddr5-tester"
				(path ""
					(reference "R134")
					(unit 1)
				)
			)
		)
	)
	(symbol
		(lib_id "antmicroResistors0402:R_1k_0402")
		(at 114.3 248.92 90)
		(unit 1)
		(exclude_from_sim no)
		(in_bom no)
		(on_board yes)
		(dnp yes)
		(property "Reference" "R130"
			(at 115.57 245.11 90)
			(effects
				(font
					(size 1.27 1.27)
					(thickness 0.15)
				)
				(justify right)
			)
		)
		(property "Value" "R_1k_0402"
			(at 127 228.6 0)
			(effects
				(font
					(size 1.27 1.27)
					(thickness 0.15)
				)
				(justify left bottom)
				(hide yes)
			)
		)
		(property "Footprint" "antmicro-footprints:R_0402_1005Metric_EIA"
			(at 129.54 228.6 0)
			(effects
				(font
					(size 1.27 1.27)
					(thickness 0.15)
				)
				(justify left bottom)
				(hide yes)
			)
		)
		(property "Datasheet" "https://www.bourns.com/docs/product-datasheets/cr.pdf"
			(at 132.08 228.6 0)
			(effects
				(font
					(size 1.27 1.27)
					(thickness 0.15)
				)
				(justify left bottom)
				(hide yes)
			)
		)
		(property "Description" ""
			(at 114.3 248.92 0)
			(effects
				(font
					(size 1.27 1.27)
				)
				(hide yes)
			)
		)
		(property "MPN" "CR0402-FX-1001GLF"
			(at 134.62 228.6 0)
			(effects
				(font
					(size 1.27 1.27)
					(thickness 0.15)
				)
				(justify left bottom)
				(hide yes)
			)
		)
		(property "Manufacturer" "Bourns"
			(at 137.16 228.6 0)
			(effects
				(font
					(size 1.27 1.27)
					(thickness 0.15)
				)
				(justify left bottom)
				(hide yes)
			)
		)
		(property "License" "Apache-2.0"
			(at 139.7 228.6 0)
			(effects
				(font
					(size 1.27 1.27)
					(thickness 0.15)
				)
				(justify left bottom)
				(hide yes)
			)
		)
		(property "Author" "Antmicro"
			(at 142.24 228.6 0)
			(effects
				(font
					(size 1.27 1.27)
					(thickness 0.15)
				)
				(justify left bottom)
				(hide yes)
			)
		)
		(property "Val" "1k"
			(at 115.57 247.65 90)
			(effects
				(font
					(size 1.27 1.27)
					(thickness 0.15)
				)
				(justify right)
			)
		)
		(property "Tolerance" "1%"
			(at 124.46 228.6 0)
			(effects
				(font
					(size 1.27 1.27)
				)
				(justify left bottom)
				(hide yes)
			)
		)
		(pin "2"
		)
		(pin "1"
		)
		(instances
			(project "data-center-rdimm-ddr5-tester"
				(path ""
					(reference "R130")
					(unit 1)
				)
			)
		)
	)
	(symbol
		(lib_id "antmicroResistors0402:R_240R_0402")
		(at 231.14 257.81 0)
		(unit 1)
		(exclude_from_sim no)
		(in_bom yes)
		(on_board yes)
		(dnp no)
		(fields_autoplaced yes)
		(property "Reference" "R180"
			(at 233.68 251.46 0)
			(effects
				(font
					(size 1.27 1.27)
					(thickness 0.15)
				)
			)
		)
		(property "Value" "R_240R_0402"
			(at 251.46 270.51 0)
			(effects
				(font
					(size 1.27 1.27)
					(thickness 0.15)
				)
				(justify left bottom)
				(hide yes)
			)
		)
		(property "Footprint" "antmicro-footprints:R_0402_1005Metric_EIA"
			(at 251.46 273.05 0)
			(effects
				(font
					(size 1.27 1.27)
					(thickness 0.15)
				)
				(justify left bottom)
				(hide yes)
			)
		)
		(property "Datasheet" "https://www.bourns.com/docs/product-datasheets/cr.pdf"
			(at 251.46 275.59 0)
			(effects
				(font
					(size 1.27 1.27)
					(thickness 0.15)
				)
				(justify left bottom)
				(hide yes)
			)
		)
		(property "Description" ""
			(at 231.14 257.81 0)
			(effects
				(font
					(size 1.27 1.27)
				)
				(hide yes)
			)
		)
		(property "MPN" "CR0402-FX-2400GLF"
			(at 251.46 278.13 0)
			(effects
				(font
					(size 1.27 1.27)
					(thickness 0.15)
				)
				(justify left bottom)
				(hide yes)
			)
		)
		(property "Manufacturer" "Bourns"
			(at 251.46 280.67 0)
			(effects
				(font
					(size 1.27 1.27)
					(thickness 0.15)
				)
				(justify left bottom)
				(hide yes)
			)
		)
		(property "License" "Apache-2.0"
			(at 251.46 283.21 0)
			(effects
				(font
					(size 1.27 1.27)
					(thickness 0.15)
				)
				(justify left bottom)
				(hide yes)
			)
		)
		(property "Author" "Antmicro"
			(at 251.46 285.75 0)
			(effects
				(font
					(size 1.27 1.27)
					(thickness 0.15)
				)
				(justify left bottom)
				(hide yes)
			)
		)
		(property "Val" "240R"
			(at 233.68 254 0)
			(effects
				(font
					(size 1.27 1.27)
					(thickness 0.15)
				)
			)
		)
		(property "Tolerance" "1%"
			(at 251.46 267.97 0)
			(effects
				(font
					(size 1.27 1.27)
				)
				(justify left bottom)
				(hide yes)
			)
		)
		(pin "1"
		)
		(pin "2"
		)
		(instances
			(project "data-center-rdimm-ddr5-tester"
				(path ""
					(reference "R180")
					(unit 1)
				)
			)
		)
	)
	(symbol
		(lib_id "antmicroFPGAChips:XCAU25P-2FFVB676I")
		(at 243.84 52.07 0)
		(unit 4)
		(exclude_from_sim no)
		(in_bom yes)
		(on_board yes)
		(dnp no)
		(property "Reference" "U34"
			(at 248.92 45.72 0)
			(effects
				(font
					(size 1.27 1.27)
					(thickness 0.15)
				)
				(justify left)
			)
		)
		(property "Value" "XCAU25P-2FFVB676I"
			(at 307.34 57.15 0)
			(effects
				(font
					(size 1.27 1.27)
					(thickness 0.15)
				)
				(justify left bottom)
				(hide yes)
			)
		)
		(property "Footprint" "antmicro-footprints:BGA-676_27x27mm_Layout26x26_P1x1mm_FFVB676"
			(at 307.34 59.69 0)
			(effects
				(font
					(size 1.27 1.27)
					(thickness 0.15)
				)
				(justify left bottom)
				(hide yes)
			)
		)
		(property "Datasheet" "https://docs.xilinx.com/viewer/book-attachment/2PXOpPtpaABIt0fkzeBLnw/hvbsEUaOT0OxFhln7VEVyA"
			(at 307.34 62.23 0)
			(effects
				(font
					(size 1.27 1.27)
					(thickness 0.15)
				)
				(justify left bottom)
				(hide yes)
			)
		)
		(property "Description" ""
			(at 243.84 52.07 0)
			(effects
				(font
					(size 1.27 1.27)
				)
				(hide yes)
			)
		)
		(property "MPN" "XCAU25P-2FFVB676I"
			(at 248.92 48.26 0)
			(effects
				(font
					(size 1.27 1.27)
					(thickness 0.15)
				)
				(justify left)
			)
		)
		(property "Manufacturer" "AMD-Xilinx"
			(at 307.34 64.77 0)
			(effects
				(font
					(size 1.27 1.27)
					(thickness 0.15)
				)
				(justify left bottom)
				(hide yes)
			)
		)
		(property "Author" "Antmicro"
			(at 307.34 67.31 0)
			(effects
				(font
					(size 1.27 1.27)
					(thickness 0.15)
				)
				(justify left bottom)
				(hide yes)
			)
		)
		(property "License" "Apache-2.0"
			(at 307.34 69.85 0)
			(effects
				(font
					(size 1.27 1.27)
					(thickness 0.15)
				)
				(justify left bottom)
				(hide yes)
			)
		)
		(pin "AC23"
		)
		(pin "P20"
		)
		(pin "N19"
		)
		(pin "AA24"
		)
		(pin "J16"
		)
		(pin "J21"
		)
		(pin "AE10"
		)
		(pin "F6"
		)
		(pin "F7"
		)
		(pin "AF17"
		)
		(pin "AA15"
		)
		(pin "J25"
		)
		(pin "Y21"
		)
		(pin "AA7"
		)
		(pin "E26"
		)
		(pin "AD16"
		)
		(pin "V1"
		)
		(pin "AB14"
		)
		(pin "Y1"
		)
		(pin "E24"
		)
		(pin "AA14"
		)
		(pin "J20"
		)
		(pin "U25"
		)
		(pin "AE18"
		)
		(pin "U22"
		)
		(pin "P4"
		)
		(pin "P5"
		)
		(pin "R1"
		)
		(pin "R10"
		)
		(pin "P8"
		)
		(pin "P9"
		)
		(pin "R11"
		)
		(pin "R12"
		)
		(pin "AD3"
		)
		(pin "AD9"
		)
		(pin "AD4"
		)
		(pin "P18"
		)
		(pin "P3"
		)
		(pin "G14"
		)
		(pin "AE26"
		)
		(pin "B12"
		)
		(pin "AC2"
		)
		(pin "W7"
		)
		(pin "W8"
		)
		(pin "W11"
		)
		(pin "W17"
		)
		(pin "W2"
		)
		(pin "W22"
		)
		(pin "W3"
		)
		(pin "W6"
		)
		(pin "P6"
		)
		(pin "U26"
		)
		(pin "P19"
		)
		(pin "U1"
		)
		(pin "U10"
		)
		(pin "J15"
		)
		(pin "AB25"
		)
		(pin "L23"
		)
		(pin "P24"
		)
		(pin "G16"
		)
		(pin "C10"
		)
		(pin "F14"
		)
		(pin "U24"
		)
		(pin "Y24"
		)
		(pin "Y11"
		)
		(pin "J26"
		)
		(pin "AB4"
		)
		(pin "AD18"
		)
		(pin "J24"
		)
		(pin "AF2"
		)
		(pin "B26"
		)
		(pin "U6"
		)
		(pin "U7"
		)
		(pin "M11"
		)
		(pin "M12"
		)
		(pin "T20"
		)
		(pin "V23"
		)
		(pin "AD10"
		)
		(pin "D1"
		)
		(pin "AF1"
		)
		(pin "C8"
		)
		(pin "U13"
		)
		(pin "U14"
		)
		(pin "AD19"
		)
		(pin "Y4"
		)
		(pin "Y5"
		)
		(pin "E23"
		)
		(pin "C6"
		)
		(pin "AE14"
		)
		(pin "D22"
		)
		(pin "C20"
		)
		(pin "AB17"
		)
		(pin "AD24"
		)
		(pin "L1"
		)
		(pin "L10"
		)
		(pin "AE3"
		)
		(pin "G21"
		)
		(pin "AA17"
		)
		(pin "D6"
		)
		(pin "M25"
		)
		(pin "R17"
		)
		(pin "R18"
		)
		(pin "AE15"
		)
		(pin "H7"
		)
		(pin "H8"
		)
		(pin "R6"
		)
		(pin "R7"
		)
		(pin "AB20"
		)
		(pin "C5"
		)
		(pin "Y14"
		)
		(pin "AE13"
		)
		(pin "C13"
		)
		(pin "W4"
		)
		(pin "P22"
		)
		(pin "AF6"
		)
		(pin "B8"
		)
		(pin "AF18"
		)
		(pin "G22"
		)
		(pin "J2"
		)
		(pin "J3"
		)
		(pin "L3"
		)
		(pin "L6"
		)
		(pin "P12"
		)
		(pin "P15"
		)
		(pin "Y12"
		)
		(pin "K18"
		)
		(pin "V10"
		)
		(pin "V11"
		)
		(pin "D7"
		)
		(pin "D8"
		)
		(pin "P23"
		)
		(pin "AA3"
		)
		(pin "AB18"
		)
		(pin "H18"
		)
		(pin "B6"
		)
		(pin "R24"
		)
		(pin "R3"
		)
		(pin "P16"
		)
		(pin "P17"
		)
		(pin "AF23"
		)
		(pin "AC14"
		)
		(pin "M6"
		)
		(pin "B18"
		)
		(pin "M1"
		)
		(pin "B5"
		)
		(pin "D2"
		)
		(pin "G20"
		)
		(pin "M2"
		)
		(pin "B4"
		)
		(pin "AA16"
		)
		(pin "V9"
		)
		(pin "W1"
		)
		(pin "N5"
		)
		(pin "AA26"
		)
		(pin "B3"
		)
		(pin "D12"
		)
		(pin "N4"
		)
		(pin "AA2"
		)
		(pin "B23"
		)
		(pin "C12"
		)
		(pin "L5"
		)
		(pin "AA6"
		)
		(pin "B1"
		)
		(pin "H1"
		)
		(pin "A14"
		)
		(pin "A13"
		)
		(pin "AB2"
		)
		(pin "AE4"
		)
		(pin "Y16"
		)
		(pin "B24"
		)
		(pin "H16"
		)
		(pin "W24"
		)
		(pin "D18"
		)
		(pin "B20"
		)
		(pin "D21"
		)
		(pin "B19"
		)
		(pin "B25"
		)
		(pin "C24"
		)
		(pin "A15"
		)
		(pin "M26"
		)
		(pin "A23"
		)
		(pin "C17"
		)
		(pin "K21"
		)
		(pin "W23"
		)
		(pin "L24"
		)
		(pin "R20"
		)
		(pin "C21"
		)
		(pin "D24"
		)
		(pin "E15"
		)
		(pin "AD12"
		)
		(pin "D23"
		)
		(pin "D25"
		)
		(pin "C26"
		)
		(pin "B21"
		)
		(pin "Y26"
		)
		(pin "AE25"
		)
		(pin "C19"
		)
		(pin "C23"
		)
		(pin "P21"
		)
		(pin "A20"
		)
		(pin "L18"
		)
		(pin "A25"
		)
		(pin "K23"
		)
		(pin "V18"
		)
		(pin "C16"
		)
		(pin "V21"
		)
		(pin "E17"
		)
		(pin "A17"
		)
		(pin "P25"
		)
		(pin "AD25"
		)
		(pin "G18"
		)
		(pin "AB3"
		)
		(pin "J6"
		)
		(pin "J7"
		)
		(pin "K12"
		)
		(pin "K13"
		)
		(pin "AB16"
		)
		(pin "C1"
		)
		(pin "AF15"
		)
		(pin "J8"
		)
		(pin "K11"
		)
		(pin "AD1"
		)
		(pin "F25"
		)
		(pin "AE1"
		)
		(pin "V2"
		)
		(pin "U2"
		)
		(pin "U3"
		)
		(pin "F2"
		)
		(pin "V6"
		)
		(pin "P1"
		)
		(pin "L13"
		)
		(pin "L14"
		)
		(pin "AD5"
		)
		(pin "AE8"
		)
		(pin "AB10"
		)
		(pin "U15"
		)
		(pin "U16"
		)
		(pin "U17"
		)
		(pin "U18"
		)
		(pin "D26"
		)
		(pin "G5"
		)
		(pin "E25"
		)
		(pin "AD22"
		)
		(pin "A19"
		)
		(pin "P7"
		)
		(pin "Y2"
		)
		(pin "J22"
		)
		(pin "Y19"
		)
		(pin "Y3"
		)
		(pin "AB7"
		)
		(pin "AF22"
		)
		(pin "B2"
		)
		(pin "AA10"
		)
		(pin "V7"
		)
		(pin "V22"
		)
		(pin "J23"
		)
		(pin "AF12"
		)
		(pin "V16"
		)
		(pin "V17"
		)
		(pin "Y7"
		)
		(pin "D15"
		)
		(pin "H12"
		)
		(pin "AF7"
		)
		(pin "U23"
		)
		(pin "V19"
		)
		(pin "AF14"
		)
		(pin "AF13"
		)
		(pin "G8"
		)
		(pin "H20"
		)
		(pin "U11"
		)
		(pin "U12"
		)
		(pin "A5"
		)
		(pin "G6"
		)
		(pin "G7"
		)
		(pin "L15"
		)
		(pin "L16"
		)
		(pin "T8"
		)
		(pin "T9"
		)
		(pin "G19"
		)
		(pin "G17"
		)
		(pin "T4"
		)
		(pin "T5"
		)
		(pin "B13"
		)
		(pin "G23"
		)
		(pin "G3"
		)
		(pin "T26"
		)
		(pin "T3"
		)
		(pin "G13"
		)
		(pin "G2"
		)
		(pin "D17"
		)
		(pin "AD15"
		)
		(pin "Y8"
		)
		(pin "Y9"
		)
		(pin "AC24"
		)
		(pin "AD8"
		)
		(pin "F8"
		)
		(pin "G1"
		)
		(pin "AD6"
		)
		(pin "F18"
		)
		(pin "H17"
		)
		(pin "AA13"
		)
		(pin "K20"
		)
		(pin "AD7"
		)
		(pin "AA1"
		)
		(pin "AF19"
		)
		(pin "Y15"
		)
		(pin "AB13"
		)
		(pin "N13"
		)
		(pin "N14"
		)
		(pin "V14"
		)
		(pin "V15"
		)
		(pin "U8"
		)
		(pin "U9"
		)
		(pin "W13"
		)
		(pin "V5"
		)
		(pin "V8"
		)
		(pin "W5"
		)
		(pin "P26"
		)
		(pin "Y20"
		)
		(pin "L17"
		)
		(pin "L2"
		)
		(pin "H26"
		)
		(pin "Y6"
		)
		(pin "AC22"
		)
		(pin "D13"
		)
		(pin "V12"
		)
		(pin "V13"
		)
		(pin "AE9"
		)
		(pin "B7"
		)
		(pin "A11"
		)
		(pin "K9"
		)
		(pin "L11"
		)
		(pin "L12"
		)
		(pin "H5"
		)
		(pin "H6"
		)
		(pin "AE19"
		)
		(pin "C18"
		)
		(pin "H13"
		)
		(pin "AB23"
		)
		(pin "AC26"
		)
		(pin "R19"
		)
		(pin "R2"
		)
		(pin "H19"
		)
		(pin "AF20"
		)
		(pin "AF24"
		)
		(pin "B22"
		)
		(pin "B14"
		)
		(pin "D4"
		)
		(pin "AA18"
		)
		(pin "C22"
		)
		(pin "V24"
		)
		(pin "A12"
		)
		(pin "C7"
		)
		(pin "M7"
		)
		(pin "AB5"
		)
		(pin "W18"
		)
		(pin "T18"
		)
		(pin "T21"
		)
		(pin "F13"
		)
		(pin "D3"
		)
		(pin "F1"
		)
		(pin "L21"
		)
		(pin "L26"
		)
		(pin "AA11"
		)
		(pin "M20"
		)
		(pin "AC4"
		)
		(pin "AE5"
		)
		(pin "D19"
		)
		(pin "E10"
		)
		(pin "AA9"
		)
		(pin "Y22"
		)
		(pin "V3"
		)
		(pin "V4"
		)
		(pin "AD2"
		)
		(pin "AC10"
		)
		(pin "C25"
		)
		(pin "G4"
		)
		(pin "A6"
		)
		(pin "E6"
		)
		(pin "E7"
		)
		(pin "E1"
		)
		(pin "E19"
		)
		(pin "R4"
		)
		(pin "T10"
		)
		(pin "T11"
		)
		(pin "J10"
		)
		(pin "F17"
		)
		(pin "A24"
		)
		(pin "AC15"
		)
		(pin "C15"
		)
		(pin "A1"
		)
		(pin "J1"
		)
		(pin "J17"
		)
		(pin "AE6"
		)
		(pin "E4"
		)
		(pin "E5"
		)
		(pin "M23"
		)
		(pin "M3"
		)
		(pin "R22"
		)
		(pin "AA5"
		)
		(pin "AC12"
		)
		(pin "Y18"
		)
		(pin "W20"
		)
		(pin "AC21"
		)
		(pin "R23"
		)
		(pin "K10"
		)
		(pin "AC17"
		)
		(pin "AC20"
		)
		(pin "V20"
		)
		(pin "V25"
		)
		(pin "N1"
		)
		(pin "N10"
		)
		(pin "M4"
		)
		(pin "M5"
		)
		(pin "R25"
		)
		(pin "H3"
		)
		(pin "H4"
		)
		(pin "AD13"
		)
		(pin "AD17"
		)
		(pin "N26"
		)
		(pin "R13"
		)
		(pin "N6"
		)
		(pin "N7"
		)
		(pin "U4"
		)
		(pin "R5"
		)
		(pin "K3"
		)
		(pin "K4"
		)
		(pin "AF3"
		)
		(pin "J5"
		)
		(pin "P2"
		)
		(pin "N22"
		)
		(pin "T16"
		)
		(pin "T17"
		)
		(pin "C3"
		)
		(pin "AF4"
		)
		(pin "T13"
		)
		(pin "AA12"
		)
		(pin "AB26"
		)
		(pin "AF21"
		)
		(pin "N25"
		)
		(pin "N3"
		)
		(pin "N21"
		)
		(pin "J12"
		)
		(pin "A8"
		)
		(pin "W12"
		)
		(pin "H14"
		)
		(pin "U21"
		)
		(pin "W9"
		)
		(pin "T14"
		)
		(pin "AE23"
		)
		(pin "K19"
		)
		(pin "K24"
		)
		(pin "Y25"
		)
		(pin "G12"
		)
		(pin "N2"
		)
		(pin "N20"
		)
		(pin "T25"
		)
		(pin "AC8"
		)
		(pin "E16"
		)
		(pin "AC19"
		)
		(pin "C14"
		)
		(pin "F4"
		)
		(pin "F5"
		)
		(pin "U19"
		)
		(pin "AE12"
		)
		(pin "P14"
		)
		(pin "AF8"
		)
		(pin "AF9"
		)
		(pin "V26"
		)
		(pin "W19"
		)
		(pin "L4"
		)
		(pin "G24"
		)
		(pin "R15"
		)
		(pin "R16"
		)
		(pin "U5"
		)
		(pin "AC16"
		)
		(pin "AF25"
		)
		(pin "T7"
		)
		(pin "F24"
		)
		(pin "D16"
		)
		(pin "AA19"
		)
		(pin "D5"
		)
		(pin "L22"
		)
		(pin "B17"
		)
		(pin "H15"
		)
		(pin "AE21"
		)
		(pin "AE7"
		)
		(pin "K5"
		)
		(pin "K6"
		)
		(pin "T1"
		)
		(pin "AE22"
		)
		(pin "E22"
		)
		(pin "AF10"
		)
		(pin "AB6"
		)
		(pin "AD26"
		)
		(pin "AC13"
		)
		(pin "E18"
		)
		(pin "M15"
		)
		(pin "M16"
		)
		(pin "G15"
		)
		(pin "N8"
		)
		(pin "N9"
		)
		(pin "W26"
		)
		(pin "F20"
		)
		(pin "AD23"
		)
		(pin "AA8"
		)
		(pin "D20"
		)
		(pin "AF11"
		)
		(pin "E8"
		)
		(pin "F11"
		)
		(pin "AC5"
		)
		(pin "AA22"
		)
		(pin "E20"
		)
		(pin "W14"
		)
		(pin "M19"
		)
		(pin "H24"
		)
		(pin "K7"
		)
		(pin "K8"
		)
		(pin "C4"
		)
		(pin "H25"
		)
		(pin "W21"
		)
		(pin "P13"
		)
		(pin "L20"
		)
		(pin "AB21"
		)
		(pin "C2"
		)
		(pin "H22"
		)
		(pin "Y17"
		)
		(pin "AE11"
		)
		(pin "H2"
		)
		(pin "F23"
		)
		(pin "E11"
		)
		(pin "AB24"
		)
		(pin "AA4"
		)
		(pin "T6"
		)
		(pin "AD20"
		)
		(pin "A10"
		)
		(pin "C9"
		)
		(pin "W15"
		)
		(pin "E21"
		)
		(pin "AB22"
		)
		(pin "W16"
		)
		(pin "AC25"
		)
		(pin "T22"
		)
		(pin "K1"
		)
		(pin "AD14"
		)
		(pin "T2"
		)
		(pin "J19"
		)
		(pin "D9"
		)
		(pin "AE17"
		)
		(pin "AB1"
		)
		(pin "T24"
		)
		(pin "F9"
		)
		(pin "M8"
		)
		(pin "M9"
		)
		(pin "Y23"
		)
		(pin "AC7"
		)
		(pin "M13"
		)
		(pin "M14"
		)
		(pin "G25"
		)
		(pin "A9"
		)
		(pin "AB19"
		)
		(pin "A7"
		)
		(pin "N15"
		)
		(pin "N16"
		)
		(pin "Y13"
		)
		(pin "AF5"
		)
		(pin "R14"
		)
		(pin "AE20"
		)
		(pin "AB11"
		)
		(pin "W25"
		)
		(pin "T19"
		)
		(pin "H21"
		)
		(pin "K2"
		)
		(pin "T23"
		)
		(pin "AC6"
		)
		(pin "B15"
		)
		(pin "E9"
		)
		(pin "AC3"
		)
		(pin "F10"
		)
		(pin "A3"
		)
		(pin "F15"
		)
		(pin "U20"
		)
		(pin "G10"
		)
		(pin "N23"
		)
		(pin "AB15"
		)
		(pin "AA21"
		)
		(pin "P10"
		)
		(pin "P11"
		)
		(pin "J11"
		)
		(pin "Y10"
		)
		(pin "F19"
		)
		(pin "A22"
		)
		(pin "AE16"
		)
		(pin "F22"
		)
		(pin "G11"
		)
		(pin "K25"
		)
		(pin "B10"
		)
		(pin "AA20"
		)
		(pin "N24"
		)
		(pin "AA25"
		)
		(pin "E12"
		)
		(pin "D11"
		)
		(pin "E14"
		)
		(pin "AC1"
		)
		(pin "J4"
		)
		(pin "H11"
		)
		(pin "H9"
		)
		(pin "M22"
		)
		(pin "H10"
		)
		(pin "E13"
		)
		(pin "AD21"
		)
		(pin "D10"
		)
		(pin "B11"
		)
		(pin "G26"
		)
		(pin "L25"
		)
		(pin "AB9"
		)
		(pin "A2"
		)
		(pin "M21"
		)
		(pin "C11"
		)
		(pin "R21"
		)
		(pin "D14"
		)
		(pin "F12"
		)
		(pin "B9"
		)
		(pin "J9"
		)
		(pin "L19"
		)
		(pin "B16"
		)
		(pin "K22"
		)
		(pin "K26"
		)
		(pin "N11"
		)
		(pin "N12"
		)
		(pin "A16"
		)
		(pin "AB12"
		)
		(pin "L7"
		)
		(pin "L8"
		)
		(pin "AC11"
		)
		(pin "J18"
		)
		(pin "K16"
		)
		(pin "K17"
		)
		(pin "M24"
		)
		(pin "M17"
		)
		(pin "M18"
		)
		(pin "J14"
		)
		(pin "R8"
		)
		(pin "R9"
		)
		(pin "A26"
		)
		(pin "H23"
		)
		(pin "AF16"
		)
		(pin "F26"
		)
		(pin "F3"
		)
		(pin "AC18"
		)
		(pin "W10"
		)
		(pin "G9"
		)
		(pin "K14"
		)
		(pin "K15"
		)
		(pin "N17"
		)
		(pin "N18"
		)
		(pin "AC9"
		)
		(pin "J13"
		)
		(pin "AE24"
		)
		(pin "AA23"
		)
		(pin "E2"
		)
		(pin "E3"
		)
		(pin "AE2"
		)
		(pin "AF26"
		)
		(pin "A21"
		)
		(pin "L9"
		)
		(pin "M10"
		)
		(pin "F16"
		)
		(pin "F21"
		)
		(pin "R26"
		)
		(pin "T12"
		)
		(pin "T15"
		)
		(pin "AB8"
		)
		(pin "A18"
		)
		(pin "A4"
		)
		(pin "AD11"
		)
		(instances
			(project "data-center-rdimm-ddr5-tester"
				(path ""
					(reference "U34")
					(unit 4)
				)
			)
		)
	)
	(symbol
		(lib_name "XCAU25P-2FFVB676I_3")
		(lib_id "antmicroFPGAChips:XCAU25P-2FFVB676I")
		(at 345.44 50.8 0)
		(unit 5)
		(exclude_from_sim no)
		(in_bom yes)
		(on_board yes)
		(dnp no)
		(property "Reference" "U34"
			(at 350.52 44.45 0)
			(effects
				(font
					(size 1.27 1.27)
					(thickness 0.15)
				)
				(justify left)
			)
		)
		(property "Value" "XCAU25P-2FFVB676I"
			(at 408.94 55.88 0)
			(effects
				(font
					(size 1.27 1.27)
					(thickness 0.15)
				)
				(justify left bottom)
				(hide yes)
			)
		)
		(property "Footprint" "antmicro-footprints:BGA-676_27x27mm_Layout26x26_P1x1mm_FFVB676"
			(at 408.94 58.42 0)
			(effects
				(font
					(size 1.27 1.27)
					(thickness 0.15)
				)
				(justify left bottom)
				(hide yes)
			)
		)
		(property "Datasheet" "https://docs.xilinx.com/viewer/book-attachment/2PXOpPtpaABIt0fkzeBLnw/hvbsEUaOT0OxFhln7VEVyA"
			(at 408.94 60.96 0)
			(effects
				(font
					(size 1.27 1.27)
					(thickness 0.15)
				)
				(justify left bottom)
				(hide yes)
			)
		)
		(property "Description" ""
			(at 345.44 50.8 0)
			(effects
				(font
					(size 1.27 1.27)
				)
				(hide yes)
			)
		)
		(property "MPN" "XCAU25P-2FFVB676I"
			(at 350.52 46.99 0)
			(effects
				(font
					(size 1.27 1.27)
					(thickness 0.15)
				)
				(justify left)
			)
		)
		(property "Manufacturer" "AMD-Xilinx"
			(at 408.94 63.5 0)
			(effects
				(font
					(size 1.27 1.27)
					(thickness 0.15)
				)
				(justify left bottom)
				(hide yes)
			)
		)
		(property "Author" "Antmicro"
			(at 408.94 66.04 0)
			(effects
				(font
					(size 1.27 1.27)
					(thickness 0.15)
				)
				(justify left bottom)
				(hide yes)
			)
		)
		(property "License" "Apache-2.0"
			(at 408.94 68.58 0)
			(effects
				(font
					(size 1.27 1.27)
					(thickness 0.15)
				)
				(justify left bottom)
				(hide yes)
			)
		)
		(pin "AC23"
		)
		(pin "P20"
		)
		(pin "N19"
		)
		(pin "AA24"
		)
		(pin "J16"
		)
		(pin "J21"
		)
		(pin "AE10"
		)
		(pin "F6"
		)
		(pin "F7"
		)
		(pin "AF17"
		)
		(pin "AA15"
		)
		(pin "J25"
		)
		(pin "Y21"
		)
		(pin "AA7"
		)
		(pin "E26"
		)
		(pin "AD16"
		)
		(pin "V1"
		)
		(pin "AB14"
		)
		(pin "Y1"
		)
		(pin "E24"
		)
		(pin "AA14"
		)
		(pin "J20"
		)
		(pin "U25"
		)
		(pin "AE18"
		)
		(pin "U22"
		)
		(pin "P4"
		)
		(pin "P5"
		)
		(pin "R1"
		)
		(pin "R10"
		)
		(pin "P8"
		)
		(pin "P9"
		)
		(pin "R11"
		)
		(pin "R12"
		)
		(pin "AD3"
		)
		(pin "AD9"
		)
		(pin "AD4"
		)
		(pin "P18"
		)
		(pin "P3"
		)
		(pin "G14"
		)
		(pin "AE26"
		)
		(pin "B12"
		)
		(pin "AC2"
		)
		(pin "W7"
		)
		(pin "W8"
		)
		(pin "W11"
		)
		(pin "W17"
		)
		(pin "W2"
		)
		(pin "W22"
		)
		(pin "W3"
		)
		(pin "W6"
		)
		(pin "P6"
		)
		(pin "U26"
		)
		(pin "P19"
		)
		(pin "U1"
		)
		(pin "U10"
		)
		(pin "J15"
		)
		(pin "AB25"
		)
		(pin "L23"
		)
		(pin "P24"
		)
		(pin "G16"
		)
		(pin "C10"
		)
		(pin "F14"
		)
		(pin "U24"
		)
		(pin "Y24"
		)
		(pin "Y11"
		)
		(pin "J26"
		)
		(pin "AB4"
		)
		(pin "AD18"
		)
		(pin "J24"
		)
		(pin "AF2"
		)
		(pin "B26"
		)
		(pin "U6"
		)
		(pin "U7"
		)
		(pin "M11"
		)
		(pin "M12"
		)
		(pin "T20"
		)
		(pin "V23"
		)
		(pin "AD10"
		)
		(pin "D1"
		)
		(pin "AF1"
		)
		(pin "C8"
		)
		(pin "U13"
		)
		(pin "U14"
		)
		(pin "AD19"
		)
		(pin "Y4"
		)
		(pin "Y5"
		)
		(pin "E23"
		)
		(pin "C6"
		)
		(pin "AE14"
		)
		(pin "D22"
		)
		(pin "C20"
		)
		(pin "AB17"
		)
		(pin "AD24"
		)
		(pin "L1"
		)
		(pin "L10"
		)
		(pin "AE3"
		)
		(pin "G21"
		)
		(pin "AA17"
		)
		(pin "D6"
		)
		(pin "M25"
		)
		(pin "R17"
		)
		(pin "R18"
		)
		(pin "AE15"
		)
		(pin "H7"
		)
		(pin "H8"
		)
		(pin "R6"
		)
		(pin "R7"
		)
		(pin "AB20"
		)
		(pin "C5"
		)
		(pin "Y14"
		)
		(pin "AE13"
		)
		(pin "C13"
		)
		(pin "W4"
		)
		(pin "P22"
		)
		(pin "AF6"
		)
		(pin "B8"
		)
		(pin "AF18"
		)
		(pin "G22"
		)
		(pin "J2"
		)
		(pin "J3"
		)
		(pin "L3"
		)
		(pin "L6"
		)
		(pin "P12"
		)
		(pin "P15"
		)
		(pin "Y12"
		)
		(pin "K18"
		)
		(pin "V10"
		)
		(pin "V11"
		)
		(pin "D7"
		)
		(pin "D8"
		)
		(pin "P23"
		)
		(pin "AA3"
		)
		(pin "AB18"
		)
		(pin "H18"
		)
		(pin "B6"
		)
		(pin "R24"
		)
		(pin "R3"
		)
		(pin "P16"
		)
		(pin "P17"
		)
		(pin "AF23"
		)
		(pin "AC14"
		)
		(pin "M6"
		)
		(pin "B18"
		)
		(pin "M1"
		)
		(pin "B5"
		)
		(pin "D2"
		)
		(pin "G20"
		)
		(pin "M2"
		)
		(pin "B4"
		)
		(pin "AA16"
		)
		(pin "V9"
		)
		(pin "W1"
		)
		(pin "N5"
		)
		(pin "AA26"
		)
		(pin "B3"
		)
		(pin "D12"
		)
		(pin "N4"
		)
		(pin "AA2"
		)
		(pin "B23"
		)
		(pin "C12"
		)
		(pin "L5"
		)
		(pin "AA6"
		)
		(pin "B1"
		)
		(pin "H1"
		)
		(pin "A14"
		)
		(pin "A13"
		)
		(pin "AB2"
		)
		(pin "AE4"
		)
		(pin "Y16"
		)
		(pin "B24"
		)
		(pin "H16"
		)
		(pin "W24"
		)
		(pin "D18"
		)
		(pin "B20"
		)
		(pin "D21"
		)
		(pin "B19"
		)
		(pin "B25"
		)
		(pin "C24"
		)
		(pin "A15"
		)
		(pin "M26"
		)
		(pin "A23"
		)
		(pin "C17"
		)
		(pin "K21"
		)
		(pin "W23"
		)
		(pin "L24"
		)
		(pin "R20"
		)
		(pin "C21"
		)
		(pin "D24"
		)
		(pin "E15"
		)
		(pin "AD12"
		)
		(pin "D23"
		)
		(pin "D25"
		)
		(pin "C26"
		)
		(pin "B21"
		)
		(pin "Y26"
		)
		(pin "AE25"
		)
		(pin "C19"
		)
		(pin "C23"
		)
		(pin "P21"
		)
		(pin "A20"
		)
		(pin "L18"
		)
		(pin "A25"
		)
		(pin "K23"
		)
		(pin "V18"
		)
		(pin "C16"
		)
		(pin "V21"
		)
		(pin "E17"
		)
		(pin "A17"
		)
		(pin "P25"
		)
		(pin "AD25"
		)
		(pin "G18"
		)
		(pin "AB3"
		)
		(pin "J6"
		)
		(pin "J7"
		)
		(pin "K12"
		)
		(pin "K13"
		)
		(pin "AB16"
		)
		(pin "C1"
		)
		(pin "AF15"
		)
		(pin "J8"
		)
		(pin "K11"
		)
		(pin "AD1"
		)
		(pin "F25"
		)
		(pin "AE1"
		)
		(pin "V2"
		)
		(pin "U2"
		)
		(pin "U3"
		)
		(pin "F2"
		)
		(pin "V6"
		)
		(pin "P1"
		)
		(pin "L13"
		)
		(pin "L14"
		)
		(pin "AD5"
		)
		(pin "AE8"
		)
		(pin "AB10"
		)
		(pin "U15"
		)
		(pin "U16"
		)
		(pin "U17"
		)
		(pin "U18"
		)
		(pin "D26"
		)
		(pin "G5"
		)
		(pin "E25"
		)
		(pin "AD22"
		)
		(pin "A19"
		)
		(pin "P7"
		)
		(pin "Y2"
		)
		(pin "J22"
		)
		(pin "Y19"
		)
		(pin "Y3"
		)
		(pin "AB7"
		)
		(pin "AF22"
		)
		(pin "B2"
		)
		(pin "AA10"
		)
		(pin "V7"
		)
		(pin "V22"
		)
		(pin "J23"
		)
		(pin "AF12"
		)
		(pin "V16"
		)
		(pin "V17"
		)
		(pin "Y7"
		)
		(pin "D15"
		)
		(pin "H12"
		)
		(pin "AF7"
		)
		(pin "U23"
		)
		(pin "V19"
		)
		(pin "AF14"
		)
		(pin "AF13"
		)
		(pin "G8"
		)
		(pin "H20"
		)
		(pin "U11"
		)
		(pin "U12"
		)
		(pin "A5"
		)
		(pin "G6"
		)
		(pin "G7"
		)
		(pin "L15"
		)
		(pin "L16"
		)
		(pin "T8"
		)
		(pin "T9"
		)
		(pin "G19"
		)
		(pin "G17"
		)
		(pin "T4"
		)
		(pin "T5"
		)
		(pin "B13"
		)
		(pin "G23"
		)
		(pin "G3"
		)
		(pin "T26"
		)
		(pin "T3"
		)
		(pin "G13"
		)
		(pin "G2"
		)
		(pin "D17"
		)
		(pin "AD15"
		)
		(pin "Y8"
		)
		(pin "Y9"
		)
		(pin "AC24"
		)
		(pin "AD8"
		)
		(pin "F8"
		)
		(pin "G1"
		)
		(pin "AD6"
		)
		(pin "F18"
		)
		(pin "H17"
		)
		(pin "AA13"
		)
		(pin "K20"
		)
		(pin "AD7"
		)
		(pin "AA1"
		)
		(pin "AF19"
		)
		(pin "Y15"
		)
		(pin "AB13"
		)
		(pin "N13"
		)
		(pin "N14"
		)
		(pin "V14"
		)
		(pin "V15"
		)
		(pin "U8"
		)
		(pin "U9"
		)
		(pin "W13"
		)
		(pin "V5"
		)
		(pin "V8"
		)
		(pin "W5"
		)
		(pin "P26"
		)
		(pin "Y20"
		)
		(pin "L17"
		)
		(pin "L2"
		)
		(pin "H26"
		)
		(pin "Y6"
		)
		(pin "AC22"
		)
		(pin "D13"
		)
		(pin "V12"
		)
		(pin "V13"
		)
		(pin "AE9"
		)
		(pin "B7"
		)
		(pin "A11"
		)
		(pin "K9"
		)
		(pin "L11"
		)
		(pin "L12"
		)
		(pin "H5"
		)
		(pin "H6"
		)
		(pin "AE19"
		)
		(pin "C18"
		)
		(pin "H13"
		)
		(pin "AB23"
		)
		(pin "AC26"
		)
		(pin "R19"
		)
		(pin "R2"
		)
		(pin "H19"
		)
		(pin "AF20"
		)
		(pin "AF24"
		)
		(pin "B22"
		)
		(pin "B14"
		)
		(pin "D4"
		)
		(pin "AA18"
		)
		(pin "C22"
		)
		(pin "V24"
		)
		(pin "A12"
		)
		(pin "C7"
		)
		(pin "M7"
		)
		(pin "AB5"
		)
		(pin "W18"
		)
		(pin "T18"
		)
		(pin "T21"
		)
		(pin "F13"
		)
		(pin "D3"
		)
		(pin "F1"
		)
		(pin "L21"
		)
		(pin "L26"
		)
		(pin "AA11"
		)
		(pin "M20"
		)
		(pin "AC4"
		)
		(pin "AE5"
		)
		(pin "D19"
		)
		(pin "E10"
		)
		(pin "AA9"
		)
		(pin "Y22"
		)
		(pin "V3"
		)
		(pin "V4"
		)
		(pin "AD2"
		)
		(pin "AC10"
		)
		(pin "C25"
		)
		(pin "G4"
		)
		(pin "A6"
		)
		(pin "E6"
		)
		(pin "E7"
		)
		(pin "E1"
		)
		(pin "E19"
		)
		(pin "R4"
		)
		(pin "T10"
		)
		(pin "T11"
		)
		(pin "J10"
		)
		(pin "F17"
		)
		(pin "A24"
		)
		(pin "AC15"
		)
		(pin "C15"
		)
		(pin "A1"
		)
		(pin "J1"
		)
		(pin "J17"
		)
		(pin "AE6"
		)
		(pin "E4"
		)
		(pin "E5"
		)
		(pin "M23"
		)
		(pin "M3"
		)
		(pin "R22"
		)
		(pin "AA5"
		)
		(pin "AC12"
		)
		(pin "Y18"
		)
		(pin "W20"
		)
		(pin "AC21"
		)
		(pin "R23"
		)
		(pin "K10"
		)
		(pin "AC17"
		)
		(pin "AC20"
		)
		(pin "V20"
		)
		(pin "V25"
		)
		(pin "N1"
		)
		(pin "N10"
		)
		(pin "M4"
		)
		(pin "M5"
		)
		(pin "R25"
		)
		(pin "H3"
		)
		(pin "H4"
		)
		(pin "AD13"
		)
		(pin "AD17"
		)
		(pin "N26"
		)
		(pin "R13"
		)
		(pin "N6"
		)
		(pin "N7"
		)
		(pin "U4"
		)
		(pin "R5"
		)
		(pin "K3"
		)
		(pin "K4"
		)
		(pin "AF3"
		)
		(pin "J5"
		)
		(pin "P2"
		)
		(pin "N22"
		)
		(pin "T16"
		)
		(pin "T17"
		)
		(pin "C3"
		)
		(pin "AF4"
		)
		(pin "T13"
		)
		(pin "AA12"
		)
		(pin "AB26"
		)
		(pin "AF21"
		)
		(pin "N25"
		)
		(pin "N3"
		)
		(pin "N21"
		)
		(pin "J12"
		)
		(pin "A8"
		)
		(pin "W12"
		)
		(pin "H14"
		)
		(pin "U21"
		)
		(pin "W9"
		)
		(pin "T14"
		)
		(pin "AE23"
		)
		(pin "K19"
		)
		(pin "K24"
		)
		(pin "Y25"
		)
		(pin "G12"
		)
		(pin "N2"
		)
		(pin "N20"
		)
		(pin "T25"
		)
		(pin "AC8"
		)
		(pin "E16"
		)
		(pin "AC19"
		)
		(pin "C14"
		)
		(pin "F4"
		)
		(pin "F5"
		)
		(pin "U19"
		)
		(pin "AE12"
		)
		(pin "P14"
		)
		(pin "AF8"
		)
		(pin "AF9"
		)
		(pin "V26"
		)
		(pin "W19"
		)
		(pin "L4"
		)
		(pin "G24"
		)
		(pin "R15"
		)
		(pin "R16"
		)
		(pin "U5"
		)
		(pin "AC16"
		)
		(pin "AF25"
		)
		(pin "T7"
		)
		(pin "F24"
		)
		(pin "D16"
		)
		(pin "AA19"
		)
		(pin "D5"
		)
		(pin "L22"
		)
		(pin "B17"
		)
		(pin "H15"
		)
		(pin "AE21"
		)
		(pin "AE7"
		)
		(pin "K5"
		)
		(pin "K6"
		)
		(pin "T1"
		)
		(pin "AE22"
		)
		(pin "E22"
		)
		(pin "AF10"
		)
		(pin "AB6"
		)
		(pin "AD26"
		)
		(pin "AC13"
		)
		(pin "E18"
		)
		(pin "M15"
		)
		(pin "M16"
		)
		(pin "G15"
		)
		(pin "N8"
		)
		(pin "N9"
		)
		(pin "W26"
		)
		(pin "F20"
		)
		(pin "AD23"
		)
		(pin "AA8"
		)
		(pin "D20"
		)
		(pin "AF11"
		)
		(pin "E8"
		)
		(pin "F11"
		)
		(pin "AC5"
		)
		(pin "AA22"
		)
		(pin "E20"
		)
		(pin "W14"
		)
		(pin "M19"
		)
		(pin "H24"
		)
		(pin "K7"
		)
		(pin "K8"
		)
		(pin "C4"
		)
		(pin "H25"
		)
		(pin "W21"
		)
		(pin "P13"
		)
		(pin "L20"
		)
		(pin "AB21"
		)
		(pin "C2"
		)
		(pin "H22"
		)
		(pin "Y17"
		)
		(pin "AE11"
		)
		(pin "H2"
		)
		(pin "F23"
		)
		(pin "E11"
		)
		(pin "AB24"
		)
		(pin "AA4"
		)
		(pin "T6"
		)
		(pin "AD20"
		)
		(pin "A10"
		)
		(pin "C9"
		)
		(pin "W15"
		)
		(pin "E21"
		)
		(pin "AB22"
		)
		(pin "W16"
		)
		(pin "AC25"
		)
		(pin "T22"
		)
		(pin "K1"
		)
		(pin "AD14"
		)
		(pin "T2"
		)
		(pin "J19"
		)
		(pin "D9"
		)
		(pin "AE17"
		)
		(pin "AB1"
		)
		(pin "T24"
		)
		(pin "F9"
		)
		(pin "M8"
		)
		(pin "M9"
		)
		(pin "Y23"
		)
		(pin "AC7"
		)
		(pin "M13"
		)
		(pin "M14"
		)
		(pin "G25"
		)
		(pin "A9"
		)
		(pin "AB19"
		)
		(pin "A7"
		)
		(pin "N15"
		)
		(pin "N16"
		)
		(pin "Y13"
		)
		(pin "AF5"
		)
		(pin "R14"
		)
		(pin "AE20"
		)
		(pin "AB11"
		)
		(pin "W25"
		)
		(pin "T19"
		)
		(pin "H21"
		)
		(pin "K2"
		)
		(pin "T23"
		)
		(pin "AC6"
		)
		(pin "B15"
		)
		(pin "E9"
		)
		(pin "AC3"
		)
		(pin "F10"
		)
		(pin "A3"
		)
		(pin "F15"
		)
		(pin "U20"
		)
		(pin "G10"
		)
		(pin "N23"
		)
		(pin "AB15"
		)
		(pin "AA21"
		)
		(pin "P10"
		)
		(pin "P11"
		)
		(pin "J11"
		)
		(pin "Y10"
		)
		(pin "F19"
		)
		(pin "A22"
		)
		(pin "AE16"
		)
		(pin "F22"
		)
		(pin "G11"
		)
		(pin "K25"
		)
		(pin "B10"
		)
		(pin "AA20"
		)
		(pin "N24"
		)
		(pin "AA25"
		)
		(pin "E12"
		)
		(pin "D11"
		)
		(pin "E14"
		)
		(pin "AC1"
		)
		(pin "J4"
		)
		(pin "H11"
		)
		(pin "H9"
		)
		(pin "M22"
		)
		(pin "H10"
		)
		(pin "E13"
		)
		(pin "AD21"
		)
		(pin "D10"
		)
		(pin "B11"
		)
		(pin "G26"
		)
		(pin "L25"
		)
		(pin "AB9"
		)
		(pin "A2"
		)
		(pin "M21"
		)
		(pin "C11"
		)
		(pin "R21"
		)
		(pin "D14"
		)
		(pin "F12"
		)
		(pin "B9"
		)
		(pin "J9"
		)
		(pin "L19"
		)
		(pin "B16"
		)
		(pin "K22"
		)
		(pin "K26"
		)
		(pin "N11"
		)
		(pin "N12"
		)
		(pin "A16"
		)
		(pin "AB12"
		)
		(pin "L7"
		)
		(pin "L8"
		)
		(pin "AC11"
		)
		(pin "J18"
		)
		(pin "K16"
		)
		(pin "K17"
		)
		(pin "M24"
		)
		(pin "M17"
		)
		(pin "M18"
		)
		(pin "J14"
		)
		(pin "R8"
		)
		(pin "R9"
		)
		(pin "A26"
		)
		(pin "H23"
		)
		(pin "AF16"
		)
		(pin "F26"
		)
		(pin "F3"
		)
		(pin "AC18"
		)
		(pin "W10"
		)
		(pin "G9"
		)
		(pin "K14"
		)
		(pin "K15"
		)
		(pin "N17"
		)
		(pin "N18"
		)
		(pin "AC9"
		)
		(pin "J13"
		)
		(pin "AE24"
		)
		(pin "AA23"
		)
		(pin "E2"
		)
		(pin "E3"
		)
		(pin "AE2"
		)
		(pin "AF26"
		)
		(pin "A21"
		)
		(pin "L9"
		)
		(pin "M10"
		)
		(pin "F16"
		)
		(pin "F21"
		)
		(pin "R26"
		)
		(pin "T12"
		)
		(pin "T15"
		)
		(pin "AB8"
		)
		(pin "A18"
		)
		(pin "A4"
		)
		(pin "AD11"
		)
		(instances
			(project "data-center-rdimm-ddr5-tester"
				(path ""
					(reference "U34")
					(unit 5)
				)
			)
		)
	)
	(symbol
		(lib_id "antmicroResistors0402:R_1k_0402")
		(at 93.98 248.92 90)
		(unit 1)
		(exclude_from_sim no)
		(in_bom no)
		(on_board yes)
		(dnp yes)
		(property "Reference" "R129"
			(at 95.25 245.11 90)
			(effects
				(font
					(size 1.27 1.27)
					(thickness 0.15)
				)
				(justify right)
			)
		)
		(property "Value" "R_1k_0402"
			(at 106.68 228.6 0)
			(effects
				(font
					(size 1.27 1.27)
					(thickness 0.15)
				)
				(justify left bottom)
				(hide yes)
			)
		)
		(property "Footprint" "antmicro-footprints:R_0402_1005Metric_EIA"
			(at 109.22 228.6 0)
			(effects
				(font
					(size 1.27 1.27)
					(thickness 0.15)
				)
				(justify left bottom)
				(hide yes)
			)
		)
		(property "Datasheet" "https://www.bourns.com/docs/product-datasheets/cr.pdf"
			(at 111.76 228.6 0)
			(effects
				(font
					(size 1.27 1.27)
					(thickness 0.15)
				)
				(justify left bottom)
				(hide yes)
			)
		)
		(property "Description" ""
			(at 93.98 248.92 0)
			(effects
				(font
					(size 1.27 1.27)
				)
				(hide yes)
			)
		)
		(property "MPN" "CR0402-FX-1001GLF"
			(at 114.3 228.6 0)
			(effects
				(font
					(size 1.27 1.27)
					(thickness 0.15)
				)
				(justify left bottom)
				(hide yes)
			)
		)
		(property "Manufacturer" "Bourns"
			(at 116.84 228.6 0)
			(effects
				(font
					(size 1.27 1.27)
					(thickness 0.15)
				)
				(justify left bottom)
				(hide yes)
			)
		)
		(property "License" "Apache-2.0"
			(at 119.38 228.6 0)
			(effects
				(font
					(size 1.27 1.27)
					(thickness 0.15)
				)
				(justify left bottom)
				(hide yes)
			)
		)
		(property "Author" "Antmicro"
			(at 121.92 228.6 0)
			(effects
				(font
					(size 1.27 1.27)
					(thickness 0.15)
				)
				(justify left bottom)
				(hide yes)
			)
		)
		(property "Val" "1k"
			(at 95.25 247.65 90)
			(effects
				(font
					(size 1.27 1.27)
					(thickness 0.15)
				)
				(justify right)
			)
		)
		(property "Tolerance" "1%"
			(at 104.14 228.6 0)
			(effects
				(font
					(size 1.27 1.27)
				)
				(justify left bottom)
				(hide yes)
			)
		)
		(pin "2"
		)
		(pin "1"
		)
		(instances
			(project "data-center-rdimm-ddr5-tester"
				(path ""
					(reference "R129")
					(unit 1)
				)
			)
		)
	)
	(symbol
		(lib_id "antmicropower:+3V3")
		(at 335.28 231.14 0)
		(unit 1)
		(exclude_from_sim no)
		(in_bom yes)
		(on_board yes)
		(dnp no)
		(property "Reference" "#PWR0264"
			(at 350.52 231.14 0)
			(effects
				(font
					(size 1.27 1.27)
					(thickness 0.15)
				)
				(justify left bottom)
				(hide yes)
			)
		)
		(property "Value" "+3V3"
			(at 335.28 227.33 0)
			(effects
				(font
					(size 1.27 1.27)
					(thickness 0.15)
				)
			)
		)
		(property "Footprint" ""
			(at 350.52 238.76 0)
			(effects
				(font
					(size 1.27 1.27)
					(thickness 0.15)
				)
				(justify left bottom)
				(hide yes)
			)
		)
		(property "Datasheet" ""
			(at 350.52 241.3 0)
			(effects
				(font
					(size 1.27 1.27)
					(thickness 0.15)
				)
				(justify left bottom)
				(hide yes)
			)
		)
		(property "Description" ""
			(at 335.28 231.14 0)
			(effects
				(font
					(size 1.27 1.27)
				)
				(hide yes)
			)
		)
		(property "Author" "Antmicro"
			(at 350.52 233.68 0)
			(effects
				(font
					(size 1.27 1.27)
					(thickness 0.15)
				)
				(justify left bottom)
				(hide yes)
			)
		)
		(property "License" "Apache-2.0"
			(at 350.52 236.22 0)
			(effects
				(font
					(size 1.27 1.27)
					(thickness 0.15)
				)
				(justify left bottom)
				(hide yes)
			)
		)
		(pin "1"
		)
		(instances
			(project "data-center-rdimm-ddr5-tester"
				(path ""
					(reference "#PWR0264")
					(unit 1)
				)
			)
		)
	)
	(symbol
		(lib_id "antmicroCapacitors0402:C_100n_0402")
		(at 83.82 243.84 90)
		(mirror x)
		(unit 1)
		(exclude_from_sim no)
		(in_bom yes)
		(on_board yes)
		(dnp no)
		(property "Reference" "C333"
			(at 85.852 245.1099 90)
			(effects
				(font
					(size 1.27 1.27)
				)
				(justify right)
			)
		)
		(property "Value" "C_100n_0402"
			(at 93.98 264.16 0)
			(effects
				(font
					(size 1.27 1.27)
					(thickness 0.15)
				)
				(justify left bottom)
				(hide yes)
			)
		)
		(property "Footprint" "antmicro-footprints:C_0402_1005Metric"
			(at 96.52 264.16 0)
			(effects
				(font
					(size 1.27 1.27)
					(thickness 0.15)
				)
				(justify left bottom)
				(hide yes)
			)
		)
		(property "Datasheet" "https://www.murata.com/products/productdetail?partno=GRM155R61H104KE14%23"
			(at 99.06 264.16 0)
			(effects
				(font
					(size 1.27 1.27)
					(thickness 0.15)
				)
				(justify left bottom)
				(hide yes)
			)
		)
		(property "Description" ""
			(at 83.82 243.84 0)
			(effects
				(font
					(size 1.27 1.27)
				)
			)
		)
		(property "Manufacturer" "Murata"
			(at 104.14 264.16 0)
			(effects
				(font
					(size 1.27 1.27)
					(thickness 0.15)
				)
				(justify left bottom)
				(hide yes)
			)
		)
		(property "MPN" "GRM155R61H104KE14D"
			(at 101.6 264.16 0)
			(effects
				(font
					(size 1.27 1.27)
					(thickness 0.15)
				)
				(justify left bottom)
				(hide yes)
			)
		)
		(property "Val" "100n"
			(at 85.852 247.65 90)
			(effects
				(font
					(size 1.27 1.27)
					(thickness 0.15)
				)
				(justify right)
			)
		)
		(property "License" "Apache-2.0"
			(at 106.68 264.16 0)
			(effects
				(font
					(size 1.27 1.27)
					(thickness 0.15)
				)
				(justify left bottom)
				(hide yes)
			)
		)
		(property "Author" "Antmicro"
			(at 109.22 264.16 0)
			(effects
				(font
					(size 1.27 1.27)
					(thickness 0.15)
				)
				(justify left bottom)
				(hide yes)
			)
		)
		(property "Voltage" "50V"
			(at 111.76 264.16 0)
			(effects
				(font
					(size 1.27 1.27)
				)
				(justify left bottom)
				(hide yes)
			)
		)
		(property "Dielectric" "X5R"
			(at 114.3 264.16 0)
			(effects
				(font
					(size 1.27 1.27)
				)
				(justify left bottom)
				(hide yes)
			)
		)
		(pin "1"
		)
		(pin "2"
		)
		(instances
			(project "data-center-rdimm-ddr5-tester"
				(path ""
					(reference "C333")
					(unit 1)
				)
			)
		)
	)
	(symbol
		(lib_id "antmicroResistors0402:R_0R_0402")
		(at 114.3 241.3 90)
		(unit 1)
		(exclude_from_sim no)
		(in_bom yes)
		(on_board yes)
		(dnp no)
		(property "Reference" "R258"
			(at 115.57 237.49 90)
			(effects
				(font
					(size 1.27 1.27)
					(thickness 0.15)
				)
				(justify right)
			)
		)
		(property "Value" "R_0R_0402"
			(at 127 220.98 0)
			(effects
				(font
					(size 1.27 1.27)
					(thickness 0.15)
				)
				(justify left bottom)
				(hide yes)
			)
		)
		(property "Footprint" "antmicro-footprints:R_0402_1005Metric"
			(at 129.54 220.98 0)
			(effects
				(font
					(size 1.27 1.27)
					(thickness 0.15)
				)
				(justify left bottom)
				(hide yes)
			)
		)
		(property "Datasheet" "https://industrial.panasonic.com/cdbs/www-data/pdf/RDA0000/AOA0000C301.pdf"
			(at 132.08 220.98 0)
			(effects
				(font
					(size 1.27 1.27)
					(thickness 0.15)
				)
				(justify left bottom)
				(hide yes)
			)
		)
		(property "Description" ""
			(at 114.3 241.3 0)
			(effects
				(font
					(size 1.27 1.27)
				)
			)
		)
		(property "MPN" "ERJ2GE0R00X"
			(at 134.62 220.98 0)
			(effects
				(font
					(size 1.27 1.27)
					(thickness 0.15)
				)
				(justify left bottom)
				(hide yes)
			)
		)
		(property "Manufacturer" "Panasonic"
			(at 137.16 220.98 0)
			(effects
				(font
					(size 1.27 1.27)
					(thickness 0.15)
				)
				(justify left bottom)
				(hide yes)
			)
		)
		(property "License" "Apache-2.0"
			(at 139.7 220.98 0)
			(effects
				(font
					(size 1.27 1.27)
					(thickness 0.15)
				)
				(justify left bottom)
				(hide yes)
			)
		)
		(property "Author" "Antmicro"
			(at 142.24 220.98 0)
			(effects
				(font
					(size 1.27 1.27)
					(thickness 0.15)
				)
				(justify left bottom)
				(hide yes)
			)
		)
		(property "Val" "0R"
			(at 115.57 240.03 90)
			(effects
				(font
					(size 1.27 1.27)
					(thickness 0.15)
				)
				(justify right)
			)
		)
		(property "Tolerance" "~"
			(at 124.46 220.98 0)
			(effects
				(font
					(size 1.27 1.27)
				)
				(justify left bottom)
				(hide yes)
			)
		)
		(property "Current" "1A"
			(at 144.78 220.98 0)
			(effects
				(font
					(size 1.27 1.27)
					(thickness 0.15)
				)
				(justify left bottom)
				(hide yes)
			)
		)
		(pin "1"
		)
		(pin "2"
		)
		(instances
			(project "data-center-rdimm-ddr5-tester"
				(path ""
					(reference "R258")
					(unit 1)
				)
			)
		)
	)
	(symbol
		(lib_id "antmicropower:GND")
		(at 260.35 260.35 0)
		(mirror y)
		(unit 1)
		(exclude_from_sim no)
		(in_bom yes)
		(on_board yes)
		(dnp no)
		(fields_autoplaced yes)
		(property "Reference" "#PWR0376"
			(at 260.35 266.7 0)
			(effects
				(font
					(size 1.27 1.27)
				)
				(hide yes)
			)
		)
		(property "Value" "GND"
			(at 262.255 264.795 0)
			(effects
				(font
					(size 1.27 1.27)
					(thickness 0.15)
				)
				(justify left bottom)
			)
		)
		(property "Footprint" ""
			(at 251.46 267.97 0)
			(effects
				(font
					(size 1.27 1.27)
					(thickness 0.15)
				)
				(justify left bottom)
				(hide yes)
			)
		)
		(property "Datasheet" ""
			(at 251.46 273.05 0)
			(effects
				(font
					(size 1.27 1.27)
					(thickness 0.15)
				)
				(justify left bottom)
				(hide yes)
			)
		)
		(property "Description" ""
			(at 260.35 260.35 0)
			(effects
				(font
					(size 1.27 1.27)
				)
				(hide yes)
			)
		)
		(property "Author" "Antmicro"
			(at 251.46 265.43 0)
			(effects
				(font
					(size 1.27 1.27)
					(thickness 0.15)
				)
				(justify left bottom)
				(hide yes)
			)
		)
		(property "License" "Apache-2.0"
			(at 251.46 267.97 0)
			(effects
				(font
					(size 1.27 1.27)
					(thickness 0.15)
				)
				(justify left bottom)
				(hide yes)
			)
		)
		(pin "1"
		)
		(instances
			(project "data-center-rdimm-ddr5-tester"
				(path ""
					(reference "#PWR0376")
					(unit 1)
				)
			)
		)
	)
	(symbol
		(lib_id "antmicropower:GND")
		(at 93.98 250.19 0)
		(mirror y)
		(unit 1)
		(exclude_from_sim no)
		(in_bom yes)
		(on_board yes)
		(dnp no)
		(fields_autoplaced yes)
		(property "Reference" "#PWR0276"
			(at 93.98 256.54 0)
			(effects
				(font
					(size 1.27 1.27)
				)
				(hide yes)
			)
		)
		(property "Value" "GND"
			(at 95.885 254.635 0)
			(effects
				(font
					(size 1.27 1.27)
					(thickness 0.15)
				)
				(justify left bottom)
			)
		)
		(property "Footprint" ""
			(at 85.09 257.81 0)
			(effects
				(font
					(size 1.27 1.27)
					(thickness 0.15)
				)
				(justify left bottom)
				(hide yes)
			)
		)
		(property "Datasheet" ""
			(at 85.09 262.89 0)
			(effects
				(font
					(size 1.27 1.27)
					(thickness 0.15)
				)
				(justify left bottom)
				(hide yes)
			)
		)
		(property "Description" ""
			(at 93.98 250.19 0)
			(effects
				(font
					(size 1.27 1.27)
				)
				(hide yes)
			)
		)
		(property "Author" "Antmicro"
			(at 85.09 255.27 0)
			(effects
				(font
					(size 1.27 1.27)
					(thickness 0.15)
				)
				(justify left bottom)
				(hide yes)
			)
		)
		(property "License" "Apache-2.0"
			(at 85.09 257.81 0)
			(effects
				(font
					(size 1.27 1.27)
					(thickness 0.15)
				)
				(justify left bottom)
				(hide yes)
			)
		)
		(pin "1"
		)
		(instances
			(project "data-center-rdimm-ddr5-tester"
				(path ""
					(reference "#PWR0276")
					(unit 1)
				)
			)
		)
	)
	(symbol
		(lib_id "antmicroResistors0402:R_0R_0402")
		(at 93.98 241.3 90)
		(unit 1)
		(exclude_from_sim no)
		(in_bom yes)
		(on_board yes)
		(dnp no)
		(property "Reference" "R257"
			(at 95.25 237.49 90)
			(effects
				(font
					(size 1.27 1.27)
					(thickness 0.15)
				)
				(justify right)
			)
		)
		(property "Value" "R_0R_0402"
			(at 106.68 220.98 0)
			(effects
				(font
					(size 1.27 1.27)
					(thickness 0.15)
				)
				(justify left bottom)
				(hide yes)
			)
		)
		(property "Footprint" "antmicro-footprints:R_0402_1005Metric"
			(at 109.22 220.98 0)
			(effects
				(font
					(size 1.27 1.27)
					(thickness 0.15)
				)
				(justify left bottom)
				(hide yes)
			)
		)
		(property "Datasheet" "https://industrial.panasonic.com/cdbs/www-data/pdf/RDA0000/AOA0000C301.pdf"
			(at 111.76 220.98 0)
			(effects
				(font
					(size 1.27 1.27)
					(thickness 0.15)
				)
				(justify left bottom)
				(hide yes)
			)
		)
		(property "Description" ""
			(at 93.98 241.3 0)
			(effects
				(font
					(size 1.27 1.27)
				)
			)
		)
		(property "MPN" "ERJ2GE0R00X"
			(at 114.3 220.98 0)
			(effects
				(font
					(size 1.27 1.27)
					(thickness 0.15)
				)
				(justify left bottom)
				(hide yes)
			)
		)
		(property "Manufacturer" "Panasonic"
			(at 116.84 220.98 0)
			(effects
				(font
					(size 1.27 1.27)
					(thickness 0.15)
				)
				(justify left bottom)
				(hide yes)
			)
		)
		(property "License" "Apache-2.0"
			(at 119.38 220.98 0)
			(effects
				(font
					(size 1.27 1.27)
					(thickness 0.15)
				)
				(justify left bottom)
				(hide yes)
			)
		)
		(property "Author" "Antmicro"
			(at 121.92 220.98 0)
			(effects
				(font
					(size 1.27 1.27)
					(thickness 0.15)
				)
				(justify left bottom)
				(hide yes)
			)
		)
		(property "Val" "0R"
			(at 95.25 240.03 90)
			(effects
				(font
					(size 1.27 1.27)
					(thickness 0.15)
				)
				(justify right)
			)
		)
		(property "Tolerance" "~"
			(at 104.14 220.98 0)
			(effects
				(font
					(size 1.27 1.27)
				)
				(justify left bottom)
				(hide yes)
			)
		)
		(property "Current" "1A"
			(at 124.46 220.98 0)
			(effects
				(font
					(size 1.27 1.27)
					(thickness 0.15)
				)
				(justify left bottom)
				(hide yes)
			)
		)
		(pin "1"
		)
		(pin "2"
		)
		(instances
			(project "data-center-rdimm-ddr5-tester"
				(path ""
					(reference "R257")
					(unit 1)
				)
			)
		)
	)
	(symbol
		(lib_id "antmicroResistors0402:R_1k_0402")
		(at 154.94 248.92 90)
		(unit 1)
		(exclude_from_sim no)
		(in_bom no)
		(on_board yes)
		(dnp yes)
		(property "Reference" "R132"
			(at 156.21 245.11 90)
			(effects
				(font
					(size 1.27 1.27)
					(thickness 0.15)
				)
				(justify right)
			)
		)
		(property "Value" "R_1k_0402"
			(at 167.64 228.6 0)
			(effects
				(font
					(size 1.27 1.27)
					(thickness 0.15)
				)
				(justify left bottom)
				(hide yes)
			)
		)
		(property "Footprint" "antmicro-footprints:R_0402_1005Metric_EIA"
			(at 170.18 228.6 0)
			(effects
				(font
					(size 1.27 1.27)
					(thickness 0.15)
				)
				(justify left bottom)
				(hide yes)
			)
		)
		(property "Datasheet" "https://www.bourns.com/docs/product-datasheets/cr.pdf"
			(at 172.72 228.6 0)
			(effects
				(font
					(size 1.27 1.27)
					(thickness 0.15)
				)
				(justify left bottom)
				(hide yes)
			)
		)
		(property "Description" ""
			(at 154.94 248.92 0)
			(effects
				(font
					(size 1.27 1.27)
				)
				(hide yes)
			)
		)
		(property "MPN" "CR0402-FX-1001GLF"
			(at 175.26 228.6 0)
			(effects
				(font
					(size 1.27 1.27)
					(thickness 0.15)
				)
				(justify left bottom)
				(hide yes)
			)
		)
		(property "Manufacturer" "Bourns"
			(at 177.8 228.6 0)
			(effects
				(font
					(size 1.27 1.27)
					(thickness 0.15)
				)
				(justify left bottom)
				(hide yes)
			)
		)
		(property "License" "Apache-2.0"
			(at 180.34 228.6 0)
			(effects
				(font
					(size 1.27 1.27)
					(thickness 0.15)
				)
				(justify left bottom)
				(hide yes)
			)
		)
		(property "Author" "Antmicro"
			(at 182.88 228.6 0)
			(effects
				(font
					(size 1.27 1.27)
					(thickness 0.15)
				)
				(justify left bottom)
				(hide yes)
			)
		)
		(property "Val" "1k"
			(at 156.21 247.65 90)
			(effects
				(font
					(size 1.27 1.27)
					(thickness 0.15)
				)
				(justify right)
			)
		)
		(property "Tolerance" "1%"
			(at 165.1 228.6 0)
			(effects
				(font
					(size 1.27 1.27)
				)
				(justify left bottom)
				(hide yes)
			)
		)
		(pin "2"
		)
		(pin "1"
		)
		(instances
			(project "data-center-rdimm-ddr5-tester"
				(path ""
					(reference "R132")
					(unit 1)
				)
			)
		)
	)
	(symbol
		(lib_id "antmicroResistors0402:R_1k_0402")
		(at 46.99 232.41 90)
		(unit 1)
		(exclude_from_sim no)
		(in_bom yes)
		(on_board yes)
		(dnp no)
		(fields_autoplaced yes)
		(property "Reference" "R253"
			(at 48.641 229.0394 90)
			(effects
				(font
					(size 1.27 1.27)
					(thickness 0.15)
				)
				(justify right)
			)
		)
		(property "Value" "R_1k_0402"
			(at 59.69 212.09 0)
			(effects
				(font
					(size 1.27 1.27)
					(thickness 0.15)
				)
				(justify left bottom)
				(hide yes)
			)
		)
		(property "Footprint" "antmicro-footprints:R_0402_1005Metric"
			(at 62.23 212.09 0)
			(effects
				(font
					(size 1.27 1.27)
					(thickness 0.15)
				)
				(justify left bottom)
				(hide yes)
			)
		)
		(property "Datasheet" "https://www.bourns.com/docs/product-datasheets/cr.pdf"
			(at 64.77 212.09 0)
			(effects
				(font
					(size 1.27 1.27)
					(thickness 0.15)
				)
				(justify left bottom)
				(hide yes)
			)
		)
		(property "Description" ""
			(at 46.99 232.41 0)
			(effects
				(font
					(size 1.27 1.27)
				)
			)
		)
		(property "MPN" "CR0402-FX-1001GLF"
			(at 67.31 212.09 0)
			(effects
				(font
					(size 1.27 1.27)
					(thickness 0.15)
				)
				(justify left bottom)
				(hide yes)
			)
		)
		(property "Manufacturer" "Bourns"
			(at 69.85 212.09 0)
			(effects
				(font
					(size 1.27 1.27)
					(thickness 0.15)
				)
				(justify left bottom)
				(hide yes)
			)
		)
		(property "License" "Apache-2.0"
			(at 72.39 212.09 0)
			(effects
				(font
					(size 1.27 1.27)
					(thickness 0.15)
				)
				(justify left bottom)
				(hide yes)
			)
		)
		(property "Author" "Antmicro"
			(at 74.93 212.09 0)
			(effects
				(font
					(size 1.27 1.27)
					(thickness 0.15)
				)
				(justify left bottom)
				(hide yes)
			)
		)
		(property "Val" "1k"
			(at 48.641 231.5631 90)
			(effects
				(font
					(size 1.27 1.27)
					(thickness 0.15)
				)
				(justify right)
			)
		)
		(property "Tolerance" "1%"
			(at 57.15 212.09 0)
			(effects
				(font
					(size 1.27 1.27)
				)
				(justify left bottom)
				(hide yes)
			)
		)
		(pin "1"
		)
		(pin "2"
		)
		(instances
			(project "data-center-rdimm-ddr5-tester"
				(path ""
					(reference "R253")
					(unit 1)
				)
			)
		)
	)
	(symbol
		(lib_id "antmicropower:GND")
		(at 104.14 250.19 0)
		(mirror y)
		(unit 1)
		(exclude_from_sim no)
		(in_bom yes)
		(on_board yes)
		(dnp no)
		(property "Reference" "#PWR0558"
			(at 104.14 256.54 0)
			(effects
				(font
					(size 1.27 1.27)
				)
				(hide yes)
			)
		)
		(property "Value" "GND"
			(at 104.14 253.746 0)
			(effects
				(font
					(size 1.27 1.27)
					(thickness 0.15)
				)
			)
		)
		(property "Footprint" ""
			(at 95.25 257.81 0)
			(effects
				(font
					(size 1.27 1.27)
					(thickness 0.15)
				)
				(justify left bottom)
				(hide yes)
			)
		)
		(property "Datasheet" ""
			(at 95.25 262.89 0)
			(effects
				(font
					(size 1.27 1.27)
					(thickness 0.15)
				)
				(justify left bottom)
				(hide yes)
			)
		)
		(property "Description" ""
			(at 95.25 265.43 0)
			(effects
				(font
					(size 1.27 1.27)
				)
				(justify left bottom)
				(hide yes)
			)
		)
		(property "Author" "Antmicro"
			(at 95.25 257.81 0)
			(effects
				(font
					(size 1.27 1.27)
					(thickness 0.15)
				)
				(justify left bottom)
				(hide yes)
			)
		)
		(property "License" "Apache-2.0"
			(at 95.25 260.35 0)
			(effects
				(font
					(size 1.27 1.27)
					(thickness 0.15)
				)
				(justify left bottom)
				(hide yes)
			)
		)
		(pin "1"
		)
		(instances
			(project "data-center-rdimm-ddr5-tester"
				(path ""
					(reference "#PWR0558")
					(unit 1)
				)
			)
		)
	)
	(symbol
		(lib_id "antmicroResistors0402:R_0R_0402")
		(at 76.2 227.33 0)
		(unit 1)
		(exclude_from_sim no)
		(in_bom yes)
		(on_board yes)
		(dnp no)
		(property "Reference" "R255"
			(at 78.74 222.756 0)
			(effects
				(font
					(size 1.27 1.27)
					(thickness 0.15)
				)
			)
		)
		(property "Value" "R_0R_0402"
			(at 96.52 240.03 0)
			(effects
				(font
					(size 1.27 1.27)
					(thickness 0.15)
				)
				(justify left bottom)
				(hide yes)
			)
		)
		(property "Footprint" "antmicro-footprints:R_0402_1005Metric"
			(at 96.52 242.57 0)
			(effects
				(font
					(size 1.27 1.27)
					(thickness 0.15)
				)
				(justify left bottom)
				(hide yes)
			)
		)
		(property "Datasheet" "https://industrial.panasonic.com/cdbs/www-data/pdf/RDA0000/AOA0000C301.pdf"
			(at 96.52 245.11 0)
			(effects
				(font
					(size 1.27 1.27)
					(thickness 0.15)
				)
				(justify left bottom)
				(hide yes)
			)
		)
		(property "Description" ""
			(at 76.2 227.33 0)
			(effects
				(font
					(size 1.27 1.27)
				)
			)
		)
		(property "MPN" "ERJ2GE0R00X"
			(at 96.52 247.65 0)
			(effects
				(font
					(size 1.27 1.27)
					(thickness 0.15)
				)
				(justify left bottom)
				(hide yes)
			)
		)
		(property "Manufacturer" "Panasonic"
			(at 96.52 250.19 0)
			(effects
				(font
					(size 1.27 1.27)
					(thickness 0.15)
				)
				(justify left bottom)
				(hide yes)
			)
		)
		(property "License" "Apache-2.0"
			(at 96.52 252.73 0)
			(effects
				(font
					(size 1.27 1.27)
					(thickness 0.15)
				)
				(justify left bottom)
				(hide yes)
			)
		)
		(property "Author" "Antmicro"
			(at 96.52 255.27 0)
			(effects
				(font
					(size 1.27 1.27)
					(thickness 0.15)
				)
				(justify left bottom)
				(hide yes)
			)
		)
		(property "Val" "0R"
			(at 78.74 225.2797 0)
			(effects
				(font
					(size 1.27 1.27)
					(thickness 0.15)
				)
			)
		)
		(property "Tolerance" "~"
			(at 96.52 237.49 0)
			(effects
				(font
					(size 1.27 1.27)
				)
				(justify left bottom)
				(hide yes)
			)
		)
		(property "Current" "1A"
			(at 96.52 257.81 0)
			(effects
				(font
					(size 1.27 1.27)
					(thickness 0.15)
				)
				(justify left bottom)
				(hide yes)
			)
		)
		(pin "1"
		)
		(pin "2"
		)
		(instances
			(project "data-center-rdimm-ddr5-tester"
				(path ""
					(reference "R255")
					(unit 1)
				)
			)
		)
	)
	(symbol
		(lib_id "antmicropower:GND")
		(at 46.99 243.84 0)
		(mirror y)
		(unit 1)
		(exclude_from_sim no)
		(in_bom yes)
		(on_board yes)
		(dnp no)
		(property "Reference" "#PWR0557"
			(at 46.99 250.19 0)
			(effects
				(font
					(size 1.27 1.27)
				)
				(hide yes)
			)
		)
		(property "Value" "GND"
			(at 46.99 247.396 0)
			(effects
				(font
					(size 1.27 1.27)
					(thickness 0.15)
				)
			)
		)
		(property "Footprint" ""
			(at 38.1 251.46 0)
			(effects
				(font
					(size 1.27 1.27)
					(thickness 0.15)
				)
				(justify left bottom)
				(hide yes)
			)
		)
		(property "Datasheet" ""
			(at 38.1 256.54 0)
			(effects
				(font
					(size 1.27 1.27)
					(thickness 0.15)
				)
				(justify left bottom)
				(hide yes)
			)
		)
		(property "Description" ""
			(at 38.1 259.08 0)
			(effects
				(font
					(size 1.27 1.27)
				)
				(justify left bottom)
				(hide yes)
			)
		)
		(property "Author" "Antmicro"
			(at 38.1 251.46 0)
			(effects
				(font
					(size 1.27 1.27)
					(thickness 0.15)
				)
				(justify left bottom)
				(hide yes)
			)
		)
		(property "License" "Apache-2.0"
			(at 38.1 254 0)
			(effects
				(font
					(size 1.27 1.27)
					(thickness 0.15)
				)
				(justify left bottom)
				(hide yes)
			)
		)
		(pin "1"
		)
		(instances
			(project "data-center-rdimm-ddr5-tester"
				(path ""
					(reference "#PWR0557")
					(unit 1)
				)
			)
		)
	)
	(symbol
		(lib_id "antmicroCapacitors0402:C_100n_0402")
		(at 104.14 243.84 90)
		(mirror x)
		(unit 1)
		(exclude_from_sim no)
		(in_bom yes)
		(on_board yes)
		(dnp no)
		(property "Reference" "C334"
			(at 104.775 244.475 90)
			(effects
				(font
					(size 1.27 1.27)
				)
				(justify right)
			)
		)
		(property "Value" "C_100n_0402"
			(at 114.3 264.16 0)
			(effects
				(font
					(size 1.27 1.27)
					(thickness 0.15)
				)
				(justify left bottom)
				(hide yes)
			)
		)
		(property "Footprint" "antmicro-footprints:C_0402_1005Metric"
			(at 116.84 264.16 0)
			(effects
				(font
					(size 1.27 1.27)
					(thickness 0.15)
				)
				(justify left bottom)
				(hide yes)
			)
		)
		(property "Datasheet" "https://www.murata.com/products/productdetail?partno=GRM155R61H104KE14%23"
			(at 119.38 264.16 0)
			(effects
				(font
					(size 1.27 1.27)
					(thickness 0.15)
				)
				(justify left bottom)
				(hide yes)
			)
		)
		(property "Description" ""
			(at 104.14 243.84 0)
			(effects
				(font
					(size 1.27 1.27)
				)
			)
		)
		(property "Manufacturer" "Murata"
			(at 124.46 264.16 0)
			(effects
				(font
					(size 1.27 1.27)
					(thickness 0.15)
				)
				(justify left bottom)
				(hide yes)
			)
		)
		(property "MPN" "GRM155R61H104KE14D"
			(at 121.92 264.16 0)
			(effects
				(font
					(size 1.27 1.27)
					(thickness 0.15)
				)
				(justify left bottom)
				(hide yes)
			)
		)
		(property "Val" "100n"
			(at 104.775 248.285 90)
			(effects
				(font
					(size 1.27 1.27)
					(thickness 0.15)
				)
				(justify right)
			)
		)
		(property "License" "Apache-2.0"
			(at 127 264.16 0)
			(effects
				(font
					(size 1.27 1.27)
					(thickness 0.15)
				)
				(justify left bottom)
				(hide yes)
			)
		)
		(property "Author" "Antmicro"
			(at 129.54 264.16 0)
			(effects
				(font
					(size 1.27 1.27)
					(thickness 0.15)
				)
				(justify left bottom)
				(hide yes)
			)
		)
		(property "Voltage" "50V"
			(at 132.08 264.16 0)
			(effects
				(font
					(size 1.27 1.27)
				)
				(justify left bottom)
				(hide yes)
			)
		)
		(property "Dielectric" "X5R"
			(at 134.62 264.16 0)
			(effects
				(font
					(size 1.27 1.27)
				)
				(justify left bottom)
				(hide yes)
			)
		)
		(pin "1"
		)
		(pin "2"
		)
		(instances
			(project "data-center-rdimm-ddr5-tester"
				(path ""
					(reference "C334")
					(unit 1)
				)
			)
		)
	)
	(symbol
		(lib_id "antmicroResistors0402:R_0R_0402")
		(at 134.62 241.3 90)
		(unit 1)
		(exclude_from_sim no)
		(in_bom yes)
		(on_board yes)
		(dnp no)
		(property "Reference" "R259"
			(at 135.89 237.49 90)
			(effects
				(font
					(size 1.27 1.27)
					(thickness 0.15)
				)
				(justify right)
			)
		)
		(property "Value" "R_0R_0402"
			(at 147.32 220.98 0)
			(effects
				(font
					(size 1.27 1.27)
					(thickness 0.15)
				)
				(justify left bottom)
				(hide yes)
			)
		)
		(property "Footprint" "antmicro-footprints:R_0402_1005Metric"
			(at 149.86 220.98 0)
			(effects
				(font
					(size 1.27 1.27)
					(thickness 0.15)
				)
				(justify left bottom)
				(hide yes)
			)
		)
		(property "Datasheet" "https://industrial.panasonic.com/cdbs/www-data/pdf/RDA0000/AOA0000C301.pdf"
			(at 152.4 220.98 0)
			(effects
				(font
					(size 1.27 1.27)
					(thickness 0.15)
				)
				(justify left bottom)
				(hide yes)
			)
		)
		(property "Description" ""
			(at 134.62 241.3 0)
			(effects
				(font
					(size 1.27 1.27)
				)
			)
		)
		(property "MPN" "ERJ2GE0R00X"
			(at 154.94 220.98 0)
			(effects
				(font
					(size 1.27 1.27)
					(thickness 0.15)
				)
				(justify left bottom)
				(hide yes)
			)
		)
		(property "Manufacturer" "Panasonic"
			(at 157.48 220.98 0)
			(effects
				(font
					(size 1.27 1.27)
					(thickness 0.15)
				)
				(justify left bottom)
				(hide yes)
			)
		)
		(property "License" "Apache-2.0"
			(at 160.02 220.98 0)
			(effects
				(font
					(size 1.27 1.27)
					(thickness 0.15)
				)
				(justify left bottom)
				(hide yes)
			)
		)
		(property "Author" "Antmicro"
			(at 162.56 220.98 0)
			(effects
				(font
					(size 1.27 1.27)
					(thickness 0.15)
				)
				(justify left bottom)
				(hide yes)
			)
		)
		(property "Val" "0R"
			(at 135.89 240.03 90)
			(effects
				(font
					(size 1.27 1.27)
					(thickness 0.15)
				)
				(justify right)
			)
		)
		(property "Tolerance" "~"
			(at 144.78 220.98 0)
			(effects
				(font
					(size 1.27 1.27)
				)
				(justify left bottom)
				(hide yes)
			)
		)
		(property "Current" "1A"
			(at 165.1 220.98 0)
			(effects
				(font
					(size 1.27 1.27)
					(thickness 0.15)
				)
				(justify left bottom)
				(hide yes)
			)
		)
		(pin "1"
		)
		(pin "2"
		)
		(instances
			(project "data-center-rdimm-ddr5-tester"
				(path ""
					(reference "R259")
					(unit 1)
				)
			)
		)
	)
	(symbol
		(lib_id "antmicropower:GND")
		(at 240.03 260.35 0)
		(mirror y)
		(unit 1)
		(exclude_from_sim no)
		(in_bom yes)
		(on_board yes)
		(dnp no)
		(fields_autoplaced yes)
		(property "Reference" "#PWR0375"
			(at 240.03 266.7 0)
			(effects
				(font
					(size 1.27 1.27)
				)
				(hide yes)
			)
		)
		(property "Value" "GND"
			(at 241.935 264.795 0)
			(effects
				(font
					(size 1.27 1.27)
					(thickness 0.15)
				)
				(justify left bottom)
			)
		)
		(property "Footprint" ""
			(at 231.14 267.97 0)
			(effects
				(font
					(size 1.27 1.27)
					(thickness 0.15)
				)
				(justify left bottom)
				(hide yes)
			)
		)
		(property "Datasheet" ""
			(at 231.14 273.05 0)
			(effects
				(font
					(size 1.27 1.27)
					(thickness 0.15)
				)
				(justify left bottom)
				(hide yes)
			)
		)
		(property "Description" ""
			(at 240.03 260.35 0)
			(effects
				(font
					(size 1.27 1.27)
				)
				(hide yes)
			)
		)
		(property "Author" "Antmicro"
			(at 231.14 265.43 0)
			(effects
				(font
					(size 1.27 1.27)
					(thickness 0.15)
				)
				(justify left bottom)
				(hide yes)
			)
		)
		(property "License" "Apache-2.0"
			(at 231.14 267.97 0)
			(effects
				(font
					(size 1.27 1.27)
					(thickness 0.15)
				)
				(justify left bottom)
				(hide yes)
			)
		)
		(pin "1"
		)
		(instances
			(project "data-center-rdimm-ddr5-tester"
				(path ""
					(reference "#PWR0375")
					(unit 1)
				)
			)
		)
	)
	(symbol
		(lib_id "antmicropower:GND")
		(at 114.3 250.19 0)
		(mirror y)
		(unit 1)
		(exclude_from_sim no)
		(in_bom yes)
		(on_board yes)
		(dnp no)
		(fields_autoplaced yes)
		(property "Reference" "#PWR0277"
			(at 114.3 256.54 0)
			(effects
				(font
					(size 1.27 1.27)
				)
				(hide yes)
			)
		)
		(property "Value" "GND"
			(at 116.205 254.635 0)
			(effects
				(font
					(size 1.27 1.27)
					(thickness 0.15)
				)
				(justify left bottom)
			)
		)
		(property "Footprint" ""
			(at 105.41 257.81 0)
			(effects
				(font
					(size 1.27 1.27)
					(thickness 0.15)
				)
				(justify left bottom)
				(hide yes)
			)
		)
		(property "Datasheet" ""
			(at 105.41 262.89 0)
			(effects
				(font
					(size 1.27 1.27)
					(thickness 0.15)
				)
				(justify left bottom)
				(hide yes)
			)
		)
		(property "Description" ""
			(at 114.3 250.19 0)
			(effects
				(font
					(size 1.27 1.27)
				)
				(hide yes)
			)
		)
		(property "Author" "Antmicro"
			(at 105.41 255.27 0)
			(effects
				(font
					(size 1.27 1.27)
					(thickness 0.15)
				)
				(justify left bottom)
				(hide yes)
			)
		)
		(property "License" "Apache-2.0"
			(at 105.41 257.81 0)
			(effects
				(font
					(size 1.27 1.27)
					(thickness 0.15)
				)
				(justify left bottom)
				(hide yes)
			)
		)
		(pin "1"
		)
		(instances
			(project "data-center-rdimm-ddr5-tester"
				(path ""
					(reference "#PWR0277")
					(unit 1)
				)
			)
		)
	)
	(symbol
		(lib_name "XCAU25P-2FFVB676I_2")
		(lib_id "antmicroFPGAChips:XCAU25P-2FFVB676I")
		(at 148.59 52.07 0)
		(unit 3)
		(exclude_from_sim no)
		(in_bom yes)
		(on_board yes)
		(dnp no)
		(property "Reference" "U34"
			(at 153.67 45.72 0)
			(effects
				(font
					(size 1.27 1.27)
					(thickness 0.15)
				)
				(justify left)
			)
		)
		(property "Value" "XCAU25P-2FFVB676I"
			(at 212.09 57.15 0)
			(effects
				(font
					(size 1.27 1.27)
					(thickness 0.15)
				)
				(justify left bottom)
				(hide yes)
			)
		)
		(property "Footprint" "antmicro-footprints:BGA-676_27x27mm_Layout26x26_P1x1mm_FFVB676"
			(at 212.09 59.69 0)
			(effects
				(font
					(size 1.27 1.27)
					(thickness 0.15)
				)
				(justify left bottom)
				(hide yes)
			)
		)
		(property "Datasheet" "https://docs.xilinx.com/viewer/book-attachment/2PXOpPtpaABIt0fkzeBLnw/hvbsEUaOT0OxFhln7VEVyA"
			(at 212.09 62.23 0)
			(effects
				(font
					(size 1.27 1.27)
					(thickness 0.15)
				)
				(justify left bottom)
				(hide yes)
			)
		)
		(property "Description" ""
			(at 148.59 52.07 0)
			(effects
				(font
					(size 1.27 1.27)
				)
				(hide yes)
			)
		)
		(property "MPN" "XCAU25P-2FFVB676I"
			(at 153.67 48.26 0)
			(effects
				(font
					(size 1.27 1.27)
					(thickness 0.15)
				)
				(justify left)
			)
		)
		(property "Manufacturer" "AMD-Xilinx"
			(at 212.09 64.77 0)
			(effects
				(font
					(size 1.27 1.27)
					(thickness 0.15)
				)
				(justify left bottom)
				(hide yes)
			)
		)
		(property "Author" "Antmicro"
			(at 212.09 67.31 0)
			(effects
				(font
					(size 1.27 1.27)
					(thickness 0.15)
				)
				(justify left bottom)
				(hide yes)
			)
		)
		(property "License" "Apache-2.0"
			(at 212.09 69.85 0)
			(effects
				(font
					(size 1.27 1.27)
					(thickness 0.15)
				)
				(justify left bottom)
				(hide yes)
			)
		)
		(pin "AC23"
		)
		(pin "P20"
		)
		(pin "N19"
		)
		(pin "AA24"
		)
		(pin "J16"
		)
		(pin "J21"
		)
		(pin "AE10"
		)
		(pin "F6"
		)
		(pin "F7"
		)
		(pin "AF17"
		)
		(pin "AA15"
		)
		(pin "J25"
		)
		(pin "Y21"
		)
		(pin "AA7"
		)
		(pin "E26"
		)
		(pin "AD16"
		)
		(pin "V1"
		)
		(pin "AB14"
		)
		(pin "Y1"
		)
		(pin "E24"
		)
		(pin "AA14"
		)
		(pin "J20"
		)
		(pin "U25"
		)
		(pin "AE18"
		)
		(pin "U22"
		)
		(pin "P4"
		)
		(pin "P5"
		)
		(pin "R1"
		)
		(pin "R10"
		)
		(pin "P8"
		)
		(pin "P9"
		)
		(pin "R11"
		)
		(pin "R12"
		)
		(pin "AD3"
		)
		(pin "AD9"
		)
		(pin "AD4"
		)
		(pin "P18"
		)
		(pin "P3"
		)
		(pin "G14"
		)
		(pin "AE26"
		)
		(pin "B12"
		)
		(pin "AC2"
		)
		(pin "W7"
		)
		(pin "W8"
		)
		(pin "W11"
		)
		(pin "W17"
		)
		(pin "W2"
		)
		(pin "W22"
		)
		(pin "W3"
		)
		(pin "W6"
		)
		(pin "P6"
		)
		(pin "U26"
		)
		(pin "P19"
		)
		(pin "U1"
		)
		(pin "U10"
		)
		(pin "J15"
		)
		(pin "AB25"
		)
		(pin "L23"
		)
		(pin "P24"
		)
		(pin "G16"
		)
		(pin "C10"
		)
		(pin "F14"
		)
		(pin "U24"
		)
		(pin "Y24"
		)
		(pin "Y11"
		)
		(pin "J26"
		)
		(pin "AB4"
		)
		(pin "AD18"
		)
		(pin "J24"
		)
		(pin "AF2"
		)
		(pin "B26"
		)
		(pin "U6"
		)
		(pin "U7"
		)
		(pin "M11"
		)
		(pin "M12"
		)
		(pin "T20"
		)
		(pin "V23"
		)
		(pin "AD10"
		)
		(pin "D1"
		)
		(pin "AF1"
		)
		(pin "C8"
		)
		(pin "U13"
		)
		(pin "U14"
		)
		(pin "AD19"
		)
		(pin "Y4"
		)
		(pin "Y5"
		)
		(pin "E23"
		)
		(pin "C6"
		)
		(pin "AE14"
		)
		(pin "D22"
		)
		(pin "C20"
		)
		(pin "AB17"
		)
		(pin "AD24"
		)
		(pin "L1"
		)
		(pin "L10"
		)
		(pin "AE3"
		)
		(pin "G21"
		)
		(pin "AA17"
		)
		(pin "D6"
		)
		(pin "M25"
		)
		(pin "R17"
		)
		(pin "R18"
		)
		(pin "AE15"
		)
		(pin "H7"
		)
		(pin "H8"
		)
		(pin "R6"
		)
		(pin "R7"
		)
		(pin "AB20"
		)
		(pin "C5"
		)
		(pin "Y14"
		)
		(pin "AE13"
		)
		(pin "C13"
		)
		(pin "W4"
		)
		(pin "P22"
		)
		(pin "AF6"
		)
		(pin "B8"
		)
		(pin "AF18"
		)
		(pin "G22"
		)
		(pin "J2"
		)
		(pin "J3"
		)
		(pin "L3"
		)
		(pin "L6"
		)
		(pin "P12"
		)
		(pin "P15"
		)
		(pin "Y12"
		)
		(pin "K18"
		)
		(pin "V10"
		)
		(pin "V11"
		)
		(pin "D7"
		)
		(pin "D8"
		)
		(pin "P23"
		)
		(pin "AA3"
		)
		(pin "AB18"
		)
		(pin "H18"
		)
		(pin "B6"
		)
		(pin "R24"
		)
		(pin "R3"
		)
		(pin "P16"
		)
		(pin "P17"
		)
		(pin "AF23"
		)
		(pin "AC14"
		)
		(pin "M6"
		)
		(pin "B18"
		)
		(pin "M1"
		)
		(pin "B5"
		)
		(pin "D2"
		)
		(pin "G20"
		)
		(pin "M2"
		)
		(pin "B4"
		)
		(pin "AA16"
		)
		(pin "V9"
		)
		(pin "W1"
		)
		(pin "N5"
		)
		(pin "AA26"
		)
		(pin "B3"
		)
		(pin "D12"
		)
		(pin "N4"
		)
		(pin "AA2"
		)
		(pin "B23"
		)
		(pin "C12"
		)
		(pin "L5"
		)
		(pin "AA6"
		)
		(pin "B1"
		)
		(pin "H1"
		)
		(pin "A14"
		)
		(pin "A13"
		)
		(pin "AB2"
		)
		(pin "AE4"
		)
		(pin "Y16"
		)
		(pin "B24"
		)
		(pin "H16"
		)
		(pin "W24"
		)
		(pin "D18"
		)
		(pin "B20"
		)
		(pin "D21"
		)
		(pin "B19"
		)
		(pin "B25"
		)
		(pin "C24"
		)
		(pin "A15"
		)
		(pin "M26"
		)
		(pin "A23"
		)
		(pin "C17"
		)
		(pin "K21"
		)
		(pin "W23"
		)
		(pin "L24"
		)
		(pin "R20"
		)
		(pin "C21"
		)
		(pin "D24"
		)
		(pin "E15"
		)
		(pin "AD12"
		)
		(pin "D23"
		)
		(pin "D25"
		)
		(pin "C26"
		)
		(pin "B21"
		)
		(pin "Y26"
		)
		(pin "AE25"
		)
		(pin "C19"
		)
		(pin "C23"
		)
		(pin "P21"
		)
		(pin "A20"
		)
		(pin "L18"
		)
		(pin "A25"
		)
		(pin "K23"
		)
		(pin "V18"
		)
		(pin "C16"
		)
		(pin "V21"
		)
		(pin "E17"
		)
		(pin "A17"
		)
		(pin "P25"
		)
		(pin "AD25"
		)
		(pin "G18"
		)
		(pin "AB3"
		)
		(pin "J6"
		)
		(pin "J7"
		)
		(pin "K12"
		)
		(pin "K13"
		)
		(pin "AB16"
		)
		(pin "C1"
		)
		(pin "AF15"
		)
		(pin "J8"
		)
		(pin "K11"
		)
		(pin "AD1"
		)
		(pin "F25"
		)
		(pin "AE1"
		)
		(pin "V2"
		)
		(pin "U2"
		)
		(pin "U3"
		)
		(pin "F2"
		)
		(pin "V6"
		)
		(pin "P1"
		)
		(pin "L13"
		)
		(pin "L14"
		)
		(pin "AD5"
		)
		(pin "AE8"
		)
		(pin "AB10"
		)
		(pin "U15"
		)
		(pin "U16"
		)
		(pin "U17"
		)
		(pin "U18"
		)
		(pin "D26"
		)
		(pin "G5"
		)
		(pin "E25"
		)
		(pin "AD22"
		)
		(pin "A19"
		)
		(pin "P7"
		)
		(pin "Y2"
		)
		(pin "J22"
		)
		(pin "Y19"
		)
		(pin "Y3"
		)
		(pin "AB7"
		)
		(pin "AF22"
		)
		(pin "B2"
		)
		(pin "AA10"
		)
		(pin "V7"
		)
		(pin "V22"
		)
		(pin "J23"
		)
		(pin "AF12"
		)
		(pin "V16"
		)
		(pin "V17"
		)
		(pin "Y7"
		)
		(pin "D15"
		)
		(pin "H12"
		)
		(pin "AF7"
		)
		(pin "U23"
		)
		(pin "V19"
		)
		(pin "AF14"
		)
		(pin "AF13"
		)
		(pin "G8"
		)
		(pin "H20"
		)
		(pin "U11"
		)
		(pin "U12"
		)
		(pin "A5"
		)
		(pin "G6"
		)
		(pin "G7"
		)
		(pin "L15"
		)
		(pin "L16"
		)
		(pin "T8"
		)
		(pin "T9"
		)
		(pin "G19"
		)
		(pin "G17"
		)
		(pin "T4"
		)
		(pin "T5"
		)
		(pin "B13"
		)
		(pin "G23"
		)
		(pin "G3"
		)
		(pin "T26"
		)
		(pin "T3"
		)
		(pin "G13"
		)
		(pin "G2"
		)
		(pin "D17"
		)
		(pin "AD15"
		)
		(pin "Y8"
		)
		(pin "Y9"
		)
		(pin "AC24"
		)
		(pin "AD8"
		)
		(pin "F8"
		)
		(pin "G1"
		)
		(pin "AD6"
		)
		(pin "F18"
		)
		(pin "H17"
		)
		(pin "AA13"
		)
		(pin "K20"
		)
		(pin "AD7"
		)
		(pin "AA1"
		)
		(pin "AF19"
		)
		(pin "Y15"
		)
		(pin "AB13"
		)
		(pin "N13"
		)
		(pin "N14"
		)
		(pin "V14"
		)
		(pin "V15"
		)
		(pin "U8"
		)
		(pin "U9"
		)
		(pin "W13"
		)
		(pin "V5"
		)
		(pin "V8"
		)
		(pin "W5"
		)
		(pin "P26"
		)
		(pin "Y20"
		)
		(pin "L17"
		)
		(pin "L2"
		)
		(pin "H26"
		)
		(pin "Y6"
		)
		(pin "AC22"
		)
		(pin "D13"
		)
		(pin "V12"
		)
		(pin "V13"
		)
		(pin "AE9"
		)
		(pin "B7"
		)
		(pin "A11"
		)
		(pin "K9"
		)
		(pin "L11"
		)
		(pin "L12"
		)
		(pin "H5"
		)
		(pin "H6"
		)
		(pin "AE19"
		)
		(pin "C18"
		)
		(pin "H13"
		)
		(pin "AB23"
		)
		(pin "AC26"
		)
		(pin "R19"
		)
		(pin "R2"
		)
		(pin "H19"
		)
		(pin "AF20"
		)
		(pin "AF24"
		)
		(pin "B22"
		)
		(pin "B14"
		)
		(pin "D4"
		)
		(pin "AA18"
		)
		(pin "C22"
		)
		(pin "V24"
		)
		(pin "A12"
		)
		(pin "C7"
		)
		(pin "M7"
		)
		(pin "AB5"
		)
		(pin "W18"
		)
		(pin "T18"
		)
		(pin "T21"
		)
		(pin "F13"
		)
		(pin "D3"
		)
		(pin "F1"
		)
		(pin "L21"
		)
		(pin "L26"
		)
		(pin "AA11"
		)
		(pin "M20"
		)
		(pin "AC4"
		)
		(pin "AE5"
		)
		(pin "D19"
		)
		(pin "E10"
		)
		(pin "AA9"
		)
		(pin "Y22"
		)
		(pin "V3"
		)
		(pin "V4"
		)
		(pin "AD2"
		)
		(pin "AC10"
		)
		(pin "C25"
		)
		(pin "G4"
		)
		(pin "A6"
		)
		(pin "E6"
		)
		(pin "E7"
		)
		(pin "E1"
		)
		(pin "E19"
		)
		(pin "R4"
		)
		(pin "T10"
		)
		(pin "T11"
		)
		(pin "J10"
		)
		(pin "F17"
		)
		(pin "A24"
		)
		(pin "AC15"
		)
		(pin "C15"
		)
		(pin "A1"
		)
		(pin "J1"
		)
		(pin "J17"
		)
		(pin "AE6"
		)
		(pin "E4"
		)
		(pin "E5"
		)
		(pin "M23"
		)
		(pin "M3"
		)
		(pin "R22"
		)
		(pin "AA5"
		)
		(pin "AC12"
		)
		(pin "Y18"
		)
		(pin "W20"
		)
		(pin "AC21"
		)
		(pin "R23"
		)
		(pin "K10"
		)
		(pin "AC17"
		)
		(pin "AC20"
		)
		(pin "V20"
		)
		(pin "V25"
		)
		(pin "N1"
		)
		(pin "N10"
		)
		(pin "M4"
		)
		(pin "M5"
		)
		(pin "R25"
		)
		(pin "H3"
		)
		(pin "H4"
		)
		(pin "AD13"
		)
		(pin "AD17"
		)
		(pin "N26"
		)
		(pin "R13"
		)
		(pin "N6"
		)
		(pin "N7"
		)
		(pin "U4"
		)
		(pin "R5"
		)
		(pin "K3"
		)
		(pin "K4"
		)
		(pin "AF3"
		)
		(pin "J5"
		)
		(pin "P2"
		)
		(pin "N22"
		)
		(pin "T16"
		)
		(pin "T17"
		)
		(pin "C3"
		)
		(pin "AF4"
		)
		(pin "T13"
		)
		(pin "AA12"
		)
		(pin "AB26"
		)
		(pin "AF21"
		)
		(pin "N25"
		)
		(pin "N3"
		)
		(pin "N21"
		)
		(pin "J12"
		)
		(pin "A8"
		)
		(pin "W12"
		)
		(pin "H14"
		)
		(pin "U21"
		)
		(pin "W9"
		)
		(pin "T14"
		)
		(pin "AE23"
		)
		(pin "K19"
		)
		(pin "K24"
		)
		(pin "Y25"
		)
		(pin "G12"
		)
		(pin "N2"
		)
		(pin "N20"
		)
		(pin "T25"
		)
		(pin "AC8"
		)
		(pin "E16"
		)
		(pin "AC19"
		)
		(pin "C14"
		)
		(pin "F4"
		)
		(pin "F5"
		)
		(pin "U19"
		)
		(pin "AE12"
		)
		(pin "P14"
		)
		(pin "AF8"
		)
		(pin "AF9"
		)
		(pin "V26"
		)
		(pin "W19"
		)
		(pin "L4"
		)
		(pin "G24"
		)
		(pin "R15"
		)
		(pin "R16"
		)
		(pin "U5"
		)
		(pin "AC16"
		)
		(pin "AF25"
		)
		(pin "T7"
		)
		(pin "F24"
		)
		(pin "D16"
		)
		(pin "AA19"
		)
		(pin "D5"
		)
		(pin "L22"
		)
		(pin "B17"
		)
		(pin "H15"
		)
		(pin "AE21"
		)
		(pin "AE7"
		)
		(pin "K5"
		)
		(pin "K6"
		)
		(pin "T1"
		)
		(pin "AE22"
		)
		(pin "E22"
		)
		(pin "AF10"
		)
		(pin "AB6"
		)
		(pin "AD26"
		)
		(pin "AC13"
		)
		(pin "E18"
		)
		(pin "M15"
		)
		(pin "M16"
		)
		(pin "G15"
		)
		(pin "N8"
		)
		(pin "N9"
		)
		(pin "W26"
		)
		(pin "F20"
		)
		(pin "AD23"
		)
		(pin "AA8"
		)
		(pin "D20"
		)
		(pin "AF11"
		)
		(pin "E8"
		)
		(pin "F11"
		)
		(pin "AC5"
		)
		(pin "AA22"
		)
		(pin "E20"
		)
		(pin "W14"
		)
		(pin "M19"
		)
		(pin "H24"
		)
		(pin "K7"
		)
		(pin "K8"
		)
		(pin "C4"
		)
		(pin "H25"
		)
		(pin "W21"
		)
		(pin "P13"
		)
		(pin "L20"
		)
		(pin "AB21"
		)
		(pin "C2"
		)
		(pin "H22"
		)
		(pin "Y17"
		)
		(pin "AE11"
		)
		(pin "H2"
		)
		(pin "F23"
		)
		(pin "E11"
		)
		(pin "AB24"
		)
		(pin "AA4"
		)
		(pin "T6"
		)
		(pin "AD20"
		)
		(pin "A10"
		)
		(pin "C9"
		)
		(pin "W15"
		)
		(pin "E21"
		)
		(pin "AB22"
		)
		(pin "W16"
		)
		(pin "AC25"
		)
		(pin "T22"
		)
		(pin "K1"
		)
		(pin "AD14"
		)
		(pin "T2"
		)
		(pin "J19"
		)
		(pin "D9"
		)
		(pin "AE17"
		)
		(pin "AB1"
		)
		(pin "T24"
		)
		(pin "F9"
		)
		(pin "M8"
		)
		(pin "M9"
		)
		(pin "Y23"
		)
		(pin "AC7"
		)
		(pin "M13"
		)
		(pin "M14"
		)
		(pin "G25"
		)
		(pin "A9"
		)
		(pin "AB19"
		)
		(pin "A7"
		)
		(pin "N15"
		)
		(pin "N16"
		)
		(pin "Y13"
		)
		(pin "AF5"
		)
		(pin "R14"
		)
		(pin "AE20"
		)
		(pin "AB11"
		)
		(pin "W25"
		)
		(pin "T19"
		)
		(pin "H21"
		)
		(pin "K2"
		)
		(pin "T23"
		)
		(pin "AC6"
		)
		(pin "B15"
		)
		(pin "E9"
		)
		(pin "AC3"
		)
		(pin "F10"
		)
		(pin "A3"
		)
		(pin "F15"
		)
		(pin "U20"
		)
		(pin "G10"
		)
		(pin "N23"
		)
		(pin "AB15"
		)
		(pin "AA21"
		)
		(pin "P10"
		)
		(pin "P11"
		)
		(pin "J11"
		)
		(pin "Y10"
		)
		(pin "F19"
		)
		(pin "A22"
		)
		(pin "AE16"
		)
		(pin "F22"
		)
		(pin "G11"
		)
		(pin "K25"
		)
		(pin "B10"
		)
		(pin "AA20"
		)
		(pin "N24"
		)
		(pin "AA25"
		)
		(pin "E12"
		)
		(pin "D11"
		)
		(pin "E14"
		)
		(pin "AC1"
		)
		(pin "J4"
		)
		(pin "H11"
		)
		(pin "H9"
		)
		(pin "M22"
		)
		(pin "H10"
		)
		(pin "E13"
		)
		(pin "AD21"
		)
		(pin "D10"
		)
		(pin "B11"
		)
		(pin "G26"
		)
		(pin "L25"
		)
		(pin "AB9"
		)
		(pin "A2"
		)
		(pin "M21"
		)
		(pin "C11"
		)
		(pin "R21"
		)
		(pin "D14"
		)
		(pin "F12"
		)
		(pin "B9"
		)
		(pin "J9"
		)
		(pin "L19"
		)
		(pin "B16"
		)
		(pin "K22"
		)
		(pin "K26"
		)
		(pin "N11"
		)
		(pin "N12"
		)
		(pin "A16"
		)
		(pin "AB12"
		)
		(pin "L7"
		)
		(pin "L8"
		)
		(pin "AC11"
		)
		(pin "J18"
		)
		(pin "K16"
		)
		(pin "K17"
		)
		(pin "M24"
		)
		(pin "M17"
		)
		(pin "M18"
		)
		(pin "J14"
		)
		(pin "R8"
		)
		(pin "R9"
		)
		(pin "A26"
		)
		(pin "H23"
		)
		(pin "AF16"
		)
		(pin "F26"
		)
		(pin "F3"
		)
		(pin "AC18"
		)
		(pin "W10"
		)
		(pin "G9"
		)
		(pin "K14"
		)
		(pin "K15"
		)
		(pin "N17"
		)
		(pin "N18"
		)
		(pin "AC9"
		)
		(pin "J13"
		)
		(pin "AE24"
		)
		(pin "AA23"
		)
		(pin "E2"
		)
		(pin "E3"
		)
		(pin "AE2"
		)
		(pin "AF26"
		)
		(pin "A21"
		)
		(pin "L9"
		)
		(pin "M10"
		)
		(pin "F16"
		)
		(pin "F21"
		)
		(pin "R26"
		)
		(pin "T12"
		)
		(pin "T15"
		)
		(pin "AB8"
		)
		(pin "A18"
		)
		(pin "A4"
		)
		(pin "AD11"
		)
		(instances
			(project "data-center-rdimm-ddr5-tester"
				(path ""
					(reference "U34")
					(unit 3)
				)
			)
		)
	)
)
